FILE_TYPE = MACRO_DRAWING;
SET COLOR_WIRE YELLOW;
SET COLOR_PROP MONO;
SET COLOR_DOT WHITE;
SET COLOR_ARC YELLOW;
SET COLOR_BODY GREEN;
SET COLOR_NOTE MONO;
SET PROP_DISPLAY VALUE;
SET PAGE_NUMBER P38;
FORCEADD PVDDQ_ABC..1
(-3075 4400);
FORCEPROP 3 LASTPIN (-3075 4350) SIG_NAME PVDDQ_ABC\g
J 0
(-3065 4360);
DISPLAY 0.659574 (-3065 4360);
PAINT MONO (-3065 4360);
DISPLAY INVISIBLE (-3065 4360);
FORCEPROP 1 LAST VOLTAGE 1.2V
J 0
(-3120 4357);
DISPLAY 0.340426 (-3120 4357);
PAINT SKYBLUE (-3120 4357);
DISPLAY INVISIBLE (-3120 4357);
FORCEPROP 2 LAST CDS_LIB mstr_symbols
J 0
(-3075 4400);
PAINT ORANGE (-3075 4400);
DISPLAY INVISIBLE (-3075 4400);
FORCEPROP 1 LAST BODY_TYPE PLUMBING
J 0
(-3120 4357);
DISPLAY 0.340426 (-3120 4357);
PAINT GREEN (-3120 4357);
DISPLAY INVISIBLE (-3120 4357);
FORCEPROP 1 LAST PATH I11
J 0
(-3025 4425);
DISPLAY 0.872340 (-3025 4425);
PAINT AQUA (-3025 4425);
DISPLAY INVISIBLE (-3025 4425);
FORCEPROP 1 LAST HDL_POWER PVDDQ_ABC
J 1
(-3075 4450);
DISPLAY 0.872340 (-3075 4450);
PAINT GREEN (-3075 4450);
DISPLAY INVISIBLE (-3075 4450);
FORCEADD PVDDQ_DEF..1
(-800 4400);
FORCEPROP 3 LASTPIN (-800 4350) SIG_NAME PVDDQ_DEF\g
J 0
(-790 4360);
DISPLAY 0.659574 (-790 4360);
PAINT MONO (-790 4360);
DISPLAY INVISIBLE (-790 4360);
FORCEPROP 1 LAST VOLTAGE 1.2V
J 0
(-845 4357);
DISPLAY 0.340426 (-845 4357);
PAINT SKYBLUE (-845 4357);
DISPLAY INVISIBLE (-845 4357);
FORCEPROP 2 LAST CDS_LIB mstr_symbols
J 0
(-800 4400);
PAINT ORANGE (-800 4400);
DISPLAY INVISIBLE (-800 4400);
FORCEPROP 1 LAST BODY_TYPE PLUMBING
J 0
(-845 4357);
DISPLAY 0.340426 (-845 4357);
PAINT GREEN (-845 4357);
DISPLAY INVISIBLE (-845 4357);
FORCEPROP 1 LAST PATH I12
J 0
(-750 4425);
DISPLAY 0.872340 (-750 4425);
PAINT AQUA (-750 4425);
DISPLAY INVISIBLE (-750 4425);
FORCEPROP 1 LAST HDL_POWER PVDDQ_DEF
J 1
(-800 4450);
DISPLAY 0.872340 (-800 4450);
PAINT GREEN (-800 4450);
DISPLAY INVISIBLE (-800 4450);
FORCEADD PVCCIO_CPU0..1
(-250 4875);
FORCEPROP 3 LASTPIN (-250 4825) SIG_NAME PVCCIO_CPU0\g
J 0
(-240 4835);
DISPLAY 0.659574 (-240 4835);
PAINT MONO (-240 4835);
DISPLAY INVISIBLE (-240 4835);
FORCEPROP 1 LAST VOLTAGE 1.1V
J 0
(-295 4832);
DISPLAY 0.340426 (-295 4832);
PAINT SKYBLUE (-295 4832);
DISPLAY INVISIBLE (-295 4832);
FORCEPROP 2 LAST CDS_LIB mstr_symbols
J 0
(-250 4875);
PAINT ORANGE (-250 4875);
DISPLAY INVISIBLE (-250 4875);
FORCEPROP 1 LAST BODY_TYPE PLUMBING
J 0
(-295 4832);
DISPLAY 0.340426 (-295 4832);
PAINT GREEN (-295 4832);
DISPLAY INVISIBLE (-295 4832);
FORCEPROP 1 LAST PATH I14
J 0
(-200 4900);
DISPLAY 0.872340 (-200 4900);
PAINT AQUA (-200 4900);
DISPLAY INVISIBLE (-200 4900);
FORCEPROP 1 LAST HDL_POWER PVCCIO_CPU0
J 1
(-250 4925);
DISPLAY 0.872340 (-250 4925);
PAINT GREEN (-250 4925);
DISPLAY INVISIBLE (-250 4925);
FORCEADD GND..1
(3000 1175);
FORCEPROP 3 LASTPIN (3000 1225) SIG_NAME GND\g
J 0
(3010 1235);
DISPLAY 0.659574 (3010 1235);
PAINT MONO (3010 1235);
DISPLAY INVISIBLE (3010 1235);
FORCEPROP 1 LAST HDL_POWER GND
J 0
(3000 1325);
DISPLAY 1.170213 (3000 1325);
PAINT GREEN (3000 1325);
DISPLAY INVISIBLE (3000 1325);
FORCEPROP 1 LAST PATH I16
J 0
(3075 1175);
DISPLAY 0.872340 (3075 1175);
PAINT AQUA (3075 1175);
DISPLAY INVISIBLE (3075 1175);
FORCEPROP 1 LAST BODY_TYPE PLUMBING
J 0
(2955 1132);
DISPLAY 0.340426 (2955 1132);
PAINT GREEN (2955 1132);
DISPLAY INVISIBLE (2955 1132);
FORCEPROP 1 LAST SIZE 1B
J 0
(3075 1125);
DISPLAY 1.170213 (3075 1125);
PAINT AQUA (3075 1125);
DISPLAY INVISIBLE (3075 1125);
FORCEPROP 2 LAST CDS_LIB mstr_symbols
J 0
(3000 1175);
PAINT ORANGE (3000 1175);
DISPLAY INVISIBLE (3000 1175);
FORCEPROP 1 LAST VOLTAGE 0.0V
J 0
(2955 1132);
DISPLAY 0.340426 (2955 1132);
PAINT SKYBLUE (2955 1132);
DISPLAY INVISIBLE (2955 1132);
FORCEADD PVCCIO_CPU0..1
(2450 1175);
FORCEPROP 3 LASTPIN (2450 1125) SIG_NAME PVCCIO_CPU0\g
J 0
(2460 1135);
DISPLAY 0.659574 (2460 1135);
PAINT MONO (2460 1135);
DISPLAY INVISIBLE (2460 1135);
FORCEPROP 1 LAST VOLTAGE 1.1V
J 0
(2405 1132);
DISPLAY 0.340426 (2405 1132);
PAINT SKYBLUE (2405 1132);
DISPLAY INVISIBLE (2405 1132);
FORCEPROP 2 LAST CDS_LIB mstr_symbols
J 0
(2450 1175);
PAINT ORANGE (2450 1175);
DISPLAY INVISIBLE (2450 1175);
FORCEPROP 1 LAST BODY_TYPE PLUMBING
J 0
(2405 1132);
DISPLAY 0.340426 (2405 1132);
PAINT GREEN (2405 1132);
DISPLAY INVISIBLE (2405 1132);
FORCEPROP 1 LAST PATH I17
J 0
(2500 1200);
DISPLAY 0.872340 (2500 1200);
PAINT AQUA (2500 1200);
DISPLAY INVISIBLE (2500 1200);
FORCEPROP 1 LAST HDL_POWER PVCCIO_CPU0
J 1
(2450 1225);
DISPLAY 0.872340 (2450 1225);
PAINT GREEN (2450 1225);
DISPLAY INVISIBLE (2450 1225);
FORCEADD CAP..1
(3000 1350);
FORCEPROP 0 LAST GROUP PWR_MCP_CAP
J 0
(3050 1100);
DISPLAY 0.638298 (3050 1100);
PAINT BROWN (3050 1100);
DISPLAY BOTH (3050 1100);
FORCEPROP 1 LASTPIN (3000 1450) $PN 1
J 0
(3010 1430);
DISPLAY 0.617021 (3010 1430);
PAINT ORANGE (3010 1430);
FORCEPROP 1 LASTPIN (3000 1250) $PN 2
J 0
(3010 1230);
DISPLAY 0.617021 (3010 1230);
PAINT ORANGE (3010 1230);
FORCEPROP 1 LAST MATERIAL X6S
J 0
(3050 1250);
DISPLAY 0.617021 (3050 1250);
PAINT SKYBLUE (3050 1250);
FORCEPROP 1 LAST VOLTAGE 4V
J 0
(3050 1350);
DISPLAY 0.617021 (3050 1350);
PAINT SKYBLUE (3050 1350);
FORCEPROP 1 LAST PACK_TYPE 0603LF
J 0
(3050 1150);
DISPLAY 0.617021 (3050 1150);
PAINT SKYBLUE (3050 1150);
FORCEPROP 1 LAST TOLERANCE 20%
J 0
(3050 1300);
DISPLAY 0.617021 (3050 1300);
PAINT SKYBLUE (3050 1300);
FORCEPROP 1 LAST VALUE 10UF
J 0
(3050 1400);
DISPLAY 0.617021 (3050 1400);
PAINT SKYBLUE (3050 1400);
FORCEPROP 1 LAST PART_NUMBER E15431-001
J 0
(3050 1200);
DISPLAY 0.617021 (3050 1200);
PAINT BLUE (3050 1200);
FORCEPROP 1 LAST LOCATION C6D1
J 0
(3050 1450);
DISPLAY 0.617021 (3050 1450);
PAINT AQUA (3050 1450);
FORCEPROP 2 LAST ROOM CPU0
J 0
(3050 1500);
DISPLAY 1.021277 (3050 1500);
PAINT ORANGE (3050 1500);
DISPLAY INVISIBLE (3050 1500);
FORCEPROP 1 LAST PATH I19
J 0
(3050 1500);
DISPLAY 0.978723 (3050 1500);
PAINT WHITE (3050 1500);
DISPLAY INVISIBLE (3050 1500);
FORCEPROP 2 LAST CDS_LOCATION C6D1
J 0
(3050 1450);
DISPLAY 0.617021 (3050 1450);
PAINT AQUA (3050 1450);
DISPLAY INVISIBLE (3050 1450);
FORCEPROP 0 LAST SEC 1
J 0
(3050 1500);
PAINT ORANGE (3050 1500);
DISPLAY INVISIBLE (3050 1500);
FORCEPROP 2 LAST BOM_COST PROC_SOCKET
J 0
(3050 1550);
DISPLAY 1.021277 (3050 1550);
PAINT ORANGE (3050 1550);
DISPLAY INVISIBLE (3050 1550);
FORCEPROP 2 LAST SEC_TYPE 0603LF
J 0
(3050 1550);
DISPLAY 1.021277 (3050 1550);
PAINT ORANGE (3050 1550);
DISPLAY INVISIBLE (3050 1550);
FORCEPROP 2 LAST CDS_LIB mstr_discrete
J 0
(3000 1350);
PAINT ORANGE (3000 1350);
DISPLAY INVISIBLE (3000 1350);
FORCEADD PVSA_CPU0..1
(2150 4950);
FORCEPROP 3 LASTPIN (2150 4900) SIG_NAME PVSA_CPU0\g
J 0
(2160 4910);
DISPLAY 0.659574 (2160 4910);
PAINT MONO (2160 4910);
DISPLAY INVISIBLE (2160 4910);
FORCEPROP 1 LAST VOLTAGE 1.1V
J 0
(2105 4907);
DISPLAY 0.340426 (2105 4907);
PAINT SKYBLUE (2105 4907);
DISPLAY INVISIBLE (2105 4907);
FORCEPROP 2 LAST CDS_LIB mstr_symbols
J 0
(2150 4950);
PAINT ORANGE (2150 4950);
DISPLAY INVISIBLE (2150 4950);
FORCEPROP 1 LAST BODY_TYPE PLUMBING
J 0
(2105 4907);
DISPLAY 0.340426 (2105 4907);
PAINT GREEN (2105 4907);
DISPLAY INVISIBLE (2105 4907);
FORCEPROP 1 LAST PATH I24
J 0
(2200 4975);
DISPLAY 0.872340 (2200 4975);
PAINT AQUA (2200 4975);
DISPLAY INVISIBLE (2200 4975);
FORCEPROP 1 LAST HDL_POWER PVSA_CPU0
J 1
(2150 5000);
DISPLAY 0.872340 (2150 5000);
PAINT GREEN (2150 5000);
DISPLAY INVISIBLE (2150 5000);
FORCEADD VCC_CORE..1
(2500 2725);
FORCEPROP 3 LASTPIN (2500 2675) SIG_NAME PVCCIOMCP_CPU0\g
J 0
(2510 2685);
DISPLAY 0.659574 (2510 2685);
PAINT MONO (2510 2685);
DISPLAY INVISIBLE (2510 2685);
FORCEPROP 1 LAST HDL_POWER PVCCIOMCP_CPU0
J 1
(2500 2775);
DISPLAY 0.617021 (2500 2775);
PAINT GREEN (2500 2775);
FORCEPROP 2 LAST CDS_LIB mstr_symbols
J 0
(2500 2725);
PAINT ORANGE (2500 2725);
DISPLAY INVISIBLE (2500 2725);
FORCEPROP 1 LAST PATH I25
J 0
(2550 2750);
DISPLAY 0.872340 (2550 2750);
PAINT AQUA (2550 2750);
DISPLAY INVISIBLE (2550 2750);
FORCEADD VCC_CORE..1
(2500 3450);
FORCEPROP 3 LASTPIN (2500 3400) SIG_NAME PVCCMCP_CPU0\g
J 0
(2510 3410);
DISPLAY 0.659574 (2510 3410);
PAINT MONO (2510 3410);
DISPLAY INVISIBLE (2510 3410);
FORCEPROP 1 LAST HDL_POWER PVCCMCP_CPU0
J 1
(2500 3500);
DISPLAY 0.617021 (2500 3500);
PAINT GREEN (2500 3500);
FORCEPROP 2 LAST CDS_LIB mstr_symbols
J 0
(2500 3450);
PAINT ORANGE (2500 3450);
DISPLAY INVISIBLE (2500 3450);
FORCEPROP 1 LAST PATH I26
J 0
(2550 3475);
DISPLAY 0.872340 (2550 3475);
PAINT AQUA (2550 3475);
DISPLAY INVISIBLE (2550 3475);
FORCEADD PVPP_ABC..1
(2325 2025);
FORCEPROP 3 LASTPIN (2325 1975) SIG_NAME PVPP_ABC\g
J 0
(2335 1985);
DISPLAY 0.659574 (2335 1985);
PAINT MONO (2335 1985);
DISPLAY INVISIBLE (2335 1985);
FORCEPROP 1 LAST VOLTAGE 2.5V
J 0
(2280 1982);
DISPLAY 0.340426 (2280 1982);
PAINT SKYBLUE (2280 1982);
DISPLAY INVISIBLE (2280 1982);
FORCEPROP 2 LAST CDS_LIB mstr_symbols
J 0
(2325 2025);
PAINT ORANGE (2325 2025);
DISPLAY INVISIBLE (2325 2025);
FORCEPROP 2 LAST BOM_COST PVPP_KLM_VR
J 0
(2400 2125);
PAINT MONO (2400 2125);
DISPLAY INVISIBLE (2400 2125);
FORCEPROP 1 LAST BODY_TYPE PLUMBING
J 0
(2280 1982);
DISPLAY 0.340426 (2280 1982);
PAINT GREEN (2280 1982);
DISPLAY INVISIBLE (2280 1982);
FORCEPROP 1 LAST PATH I31
J 0
(2375 2050);
DISPLAY 0.872340 (2375 2050);
PAINT AQUA (2375 2050);
DISPLAY INVISIBLE (2375 2050);
FORCEPROP 2 LAST ROOM PVPP_KLM_VR
J 0
(2575 2125);
PAINT ORANGE (2575 2125);
DISPLAY INVISIBLE (2575 2125);
FORCEPROP 1 LAST HDL_POWER PVPP_ABC
J 1
(2325 2075);
DISPLAY 0.872340 (2325 2075);
PAINT GREEN (2325 2075);
DISPLAY INVISIBLE (2325 2075);
FORCEADD SKX_EXT_B..20
(-1950 2650);
FORCEPROP 1 LAST PART_NUMBER TBD
J 0
(-2750 1150);
DISPLAY 0.617021 (-2750 1150);
PAINT BLUE (-2750 1150);
FORCEPROP 1 LAST MATERIAL IC
J 0
(-2750 4150);
DISPLAY 0.617021 (-2750 4150);
PAINT SKYBLUE (-2750 4150);
FORCEPROP 2 LASTPIN (-1100 3950) $PN EE44
J 0
(-1090 3960);
DISPLAY 0.617021 (-1090 3960);
PAINT ORANGE (-1090 3960);
FORCEPROP 2 LASTPIN (-1100 3900) $PN EF45
J 0
(-1090 3910);
DISPLAY 0.617021 (-1090 3910);
PAINT ORANGE (-1090 3910);
FORCEPROP 2 LASTPIN (-1100 3850) $PN DB53
J 0
(-1090 3860);
DISPLAY 0.617021 (-1090 3860);
PAINT ORANGE (-1090 3860);
FORCEPROP 2 LASTPIN (-1100 3800) $PN DB55
J 0
(-1090 3810);
DISPLAY 0.617021 (-1090 3810);
PAINT ORANGE (-1090 3810);
FORCEPROP 2 LASTPIN (-1100 3750) $PN DB57
J 0
(-1090 3760);
DISPLAY 0.617021 (-1090 3760);
PAINT ORANGE (-1090 3760);
FORCEPROP 2 LASTPIN (-1100 3700) $PN DB59
J 0
(-1090 3710);
DISPLAY 0.617021 (-1090 3710);
PAINT ORANGE (-1090 3710);
FORCEPROP 2 LASTPIN (-1100 3650) $PN DB61
J 0
(-1090 3660);
DISPLAY 0.617021 (-1090 3660);
PAINT ORANGE (-1090 3660);
FORCEPROP 2 LASTPIN (-1100 3600) $PN DB63
J 0
(-1090 3610);
DISPLAY 0.617021 (-1090 3610);
PAINT ORANGE (-1090 3610);
FORCEPROP 2 LASTPIN (-1100 3550) $PN DD45
J 0
(-1090 3560);
DISPLAY 0.617021 (-1090 3560);
PAINT ORANGE (-1090 3560);
FORCEPROP 2 LASTPIN (-1100 3500) $PN DH45
J 0
(-1090 3510);
DISPLAY 0.617021 (-1090 3510);
PAINT ORANGE (-1090 3510);
FORCEPROP 2 LASTPIN (-1100 3450) $PN DH47
J 0
(-1090 3460);
DISPLAY 0.617021 (-1090 3460);
PAINT ORANGE (-1090 3460);
FORCEPROP 2 LASTPIN (-1100 3400) $PN DH49
J 0
(-1090 3410);
DISPLAY 0.617021 (-1090 3410);
PAINT ORANGE (-1090 3410);
FORCEPROP 2 LASTPIN (-1100 3350) $PN DH51
J 0
(-1090 3360);
DISPLAY 0.617021 (-1090 3360);
PAINT ORANGE (-1090 3360);
FORCEPROP 2 LASTPIN (-1100 3300) $PN DH53
J 0
(-1090 3310);
DISPLAY 0.617021 (-1090 3310);
PAINT ORANGE (-1090 3310);
FORCEPROP 2 LASTPIN (-1100 3250) $PN DH55
J 0
(-1090 3260);
DISPLAY 0.617021 (-1090 3260);
PAINT ORANGE (-1090 3260);
FORCEPROP 2 LASTPIN (-1100 3200) $PN DH57
J 0
(-1090 3210);
DISPLAY 0.617021 (-1090 3210);
PAINT ORANGE (-1090 3210);
FORCEPROP 2 LASTPIN (-1100 3150) $PN DH59
J 0
(-1090 3160);
DISPLAY 0.617021 (-1090 3160);
PAINT ORANGE (-1090 3160);
FORCEPROP 2 LASTPIN (-1100 3000) $PN DJ64
J 0
(-1090 3010);
DISPLAY 0.617021 (-1090 3010);
PAINT ORANGE (-1090 3010);
FORCEPROP 2 LASTPIN (-1100 2950) $PN DL46
J 0
(-1090 2960);
DISPLAY 0.617021 (-1090 2960);
PAINT ORANGE (-1090 2960);
FORCEPROP 2 LASTPIN (-1100 2900) $PN DL48
J 0
(-1090 2910);
DISPLAY 0.617021 (-1090 2910);
PAINT ORANGE (-1090 2910);
FORCEPROP 2 LASTPIN (-1100 2850) $PN DL50
J 0
(-1090 2860);
DISPLAY 0.617021 (-1090 2860);
PAINT ORANGE (-1090 2860);
FORCEPROP 2 LASTPIN (-1100 2800) $PN DL52
J 0
(-1090 2810);
DISPLAY 0.617021 (-1090 2810);
PAINT ORANGE (-1090 2810);
FORCEPROP 2 LASTPIN (-1100 2750) $PN DL54
J 0
(-1090 2760);
DISPLAY 0.617021 (-1090 2760);
PAINT ORANGE (-1090 2760);
FORCEPROP 2 LASTPIN (-1100 2700) $PN DL56
J 0
(-1090 2710);
DISPLAY 0.617021 (-1090 2710);
PAINT ORANGE (-1090 2710);
FORCEPROP 2 LASTPIN (-1100 2650) $PN DL58
J 0
(-1090 2660);
DISPLAY 0.617021 (-1090 2660);
PAINT ORANGE (-1090 2660);
FORCEPROP 2 LASTPIN (-1100 2600) $PN DL60
J 0
(-1090 2610);
DISPLAY 0.617021 (-1090 2610);
PAINT ORANGE (-1090 2610);
FORCEPROP 2 LASTPIN (-1100 2550) $PN DL62
J 0
(-1090 2560);
DISPLAY 0.617021 (-1090 2560);
PAINT ORANGE (-1090 2560);
FORCEPROP 2 LASTPIN (-1100 2500) $PN DU46
J 0
(-1090 2510);
DISPLAY 0.617021 (-1090 2510);
PAINT ORANGE (-1090 2510);
FORCEPROP 2 LASTPIN (-1100 2450) $PN DU48
J 0
(-1090 2460);
DISPLAY 0.617021 (-1090 2460);
PAINT ORANGE (-1090 2460);
FORCEPROP 2 LASTPIN (-1100 2400) $PN DU50
J 0
(-1090 2410);
DISPLAY 0.617021 (-1090 2410);
PAINT ORANGE (-1090 2410);
FORCEPROP 2 LASTPIN (-1100 2350) $PN DU52
J 0
(-1090 2360);
DISPLAY 0.617021 (-1090 2360);
PAINT ORANGE (-1090 2360);
FORCEPROP 2 LASTPIN (-1100 2300) $PN DU54
J 0
(-1090 2310);
DISPLAY 0.617021 (-1090 2310);
PAINT ORANGE (-1090 2310);
FORCEPROP 2 LASTPIN (-1100 2250) $PN DU56
J 0
(-1090 2260);
DISPLAY 0.617021 (-1090 2260);
PAINT ORANGE (-1090 2260);
FORCEPROP 2 LASTPIN (-1100 2200) $PN DU58
J 0
(-1090 2210);
DISPLAY 0.617021 (-1090 2210);
PAINT ORANGE (-1090 2210);
FORCEPROP 2 LASTPIN (-1100 2150) $PN DU60
J 0
(-1090 2160);
DISPLAY 0.617021 (-1090 2160);
PAINT ORANGE (-1090 2160);
FORCEPROP 2 LASTPIN (-1100 2100) $PN DU62
J 0
(-1090 2110);
DISPLAY 0.617021 (-1090 2110);
PAINT ORANGE (-1090 2110);
FORCEPROP 2 LASTPIN (-1100 2050) $PN DU64
J 0
(-1090 2060);
DISPLAY 0.617021 (-1090 2060);
PAINT ORANGE (-1090 2060);
FORCEPROP 2 LASTPIN (-1100 2000) $PN EC46
J 0
(-1090 2010);
DISPLAY 0.617021 (-1090 2010);
PAINT ORANGE (-1090 2010);
FORCEPROP 2 LASTPIN (-1100 1950) $PN EC48
J 0
(-1090 1960);
DISPLAY 0.617021 (-1090 1960);
PAINT ORANGE (-1090 1960);
FORCEPROP 2 LASTPIN (-1100 1900) $PN EC50
J 0
(-1090 1910);
DISPLAY 0.617021 (-1090 1910);
PAINT ORANGE (-1090 1910);
FORCEPROP 2 LASTPIN (-1100 1850) $PN EC52
J 0
(-1090 1860);
DISPLAY 0.617021 (-1090 1860);
PAINT ORANGE (-1090 1860);
FORCEPROP 2 LASTPIN (-1100 1800) $PN EC54
J 0
(-1090 1810);
DISPLAY 0.617021 (-1090 1810);
PAINT ORANGE (-1090 1810);
FORCEPROP 2 LASTPIN (-1100 1750) $PN EC56
J 0
(-1090 1760);
DISPLAY 0.617021 (-1090 1760);
PAINT ORANGE (-1090 1760);
FORCEPROP 2 LASTPIN (-1100 1700) $PN EC58
J 0
(-1090 1710);
DISPLAY 0.617021 (-1090 1710);
PAINT ORANGE (-1090 1710);
FORCEPROP 2 LASTPIN (-1100 1650) $PN EC60
J 0
(-1090 1660);
DISPLAY 0.617021 (-1090 1660);
PAINT ORANGE (-1090 1660);
FORCEPROP 2 LASTPIN (-1100 1600) $PN EC62
J 0
(-1090 1610);
DISPLAY 0.617021 (-1090 1610);
PAINT ORANGE (-1090 1610);
FORCEPROP 2 LASTPIN (-1100 1550) $PN EF49
J 0
(-1090 1560);
DISPLAY 0.617021 (-1090 1560);
PAINT ORANGE (-1090 1560);
FORCEPROP 2 LASTPIN (-1100 1400) $PN EF59
J 0
(-1090 1410);
DISPLAY 0.617021 (-1090 1410);
PAINT ORANGE (-1090 1410);
FORCEPROP 2 LASTPIN (-2800 3950) $PN B47
J 2
(-2810 3960);
DISPLAY 0.617021 (-2810 3960);
PAINT ORANGE (-2810 3960);
FORCEPROP 2 LASTPIN (-2800 3900) $PN C46
J 2
(-2810 3910);
DISPLAY 0.617021 (-2810 3910);
PAINT ORANGE (-2810 3910);
FORCEPROP 2 LASTPIN (-2800 3850) $PN D45
J 2
(-2810 3860);
DISPLAY 0.617021 (-2810 3860);
PAINT ORANGE (-2810 3860);
FORCEPROP 2 LASTPIN (-2800 3800) $PN AF63
J 2
(-2810 3810);
DISPLAY 0.617021 (-2810 3810);
PAINT ORANGE (-2810 3810);
FORCEPROP 2 LASTPIN (-2800 3750) $PN AF61
J 2
(-2810 3760);
DISPLAY 0.617021 (-2810 3760);
PAINT ORANGE (-2810 3760);
FORCEPROP 2 LASTPIN (-2800 3700) $PN AF59
J 2
(-2810 3710);
DISPLAY 0.617021 (-2810 3710);
PAINT ORANGE (-2810 3710);
FORCEPROP 2 LASTPIN (-2800 3650) $PN AF57
J 2
(-2810 3660);
DISPLAY 0.617021 (-2810 3660);
PAINT ORANGE (-2810 3660);
FORCEPROP 2 LASTPIN (-2800 3600) $PN AF55
J 2
(-2810 3610);
DISPLAY 0.617021 (-2810 3610);
PAINT ORANGE (-2810 3610);
FORCEPROP 2 LASTPIN (-2800 3550) $PN AD45
J 2
(-2810 3560);
DISPLAY 0.617021 (-2810 3560);
PAINT ORANGE (-2810 3560);
FORCEPROP 2 LASTPIN (-2800 3500) $PN Y63
J 2
(-2810 3510);
DISPLAY 0.617021 (-2810 3510);
PAINT ORANGE (-2810 3510);
FORCEPROP 2 LASTPIN (-2800 3450) $PN Y61
J 2
(-2810 3460);
DISPLAY 0.617021 (-2810 3460);
PAINT ORANGE (-2810 3460);
FORCEPROP 2 LASTPIN (-2800 3400) $PN Y59
J 2
(-2810 3410);
DISPLAY 0.617021 (-2810 3410);
PAINT ORANGE (-2810 3410);
FORCEPROP 2 LASTPIN (-2800 3350) $PN Y57
J 2
(-2810 3360);
DISPLAY 0.617021 (-2810 3360);
PAINT ORANGE (-2810 3360);
FORCEPROP 2 LASTPIN (-2800 3300) $PN Y55
J 2
(-2810 3310);
DISPLAY 0.617021 (-2810 3310);
PAINT ORANGE (-2810 3310);
FORCEPROP 2 LASTPIN (-2800 3250) $PN Y53
J 2
(-2810 3260);
DISPLAY 0.617021 (-2810 3260);
PAINT ORANGE (-2810 3260);
FORCEPROP 2 LASTPIN (-2800 3200) $PN Y51
J 2
(-2810 3210);
DISPLAY 0.617021 (-2810 3210);
PAINT ORANGE (-2810 3210);
FORCEPROP 2 LASTPIN (-2800 3150) $PN Y49
J 2
(-2810 3160);
DISPLAY 0.617021 (-2810 3160);
PAINT ORANGE (-2810 3160);
FORCEPROP 2 LASTPIN (-2800 3100) $PN Y47
J 2
(-2810 3110);
DISPLAY 0.617021 (-2810 3110);
PAINT ORANGE (-2810 3110);
FORCEPROP 2 LASTPIN (-2800 3050) $PN Y45
J 2
(-2810 3060);
DISPLAY 0.617021 (-2810 3060);
PAINT ORANGE (-2810 3060);
FORCEPROP 2 LASTPIN (-2800 3000) $PN W64
J 2
(-2810 3010);
DISPLAY 0.617021 (-2810 3010);
PAINT ORANGE (-2810 3010);
FORCEPROP 2 LASTPIN (-2800 2950) $PN U62
J 2
(-2810 2960);
DISPLAY 0.617021 (-2810 2960);
PAINT ORANGE (-2810 2960);
FORCEPROP 2 LASTPIN (-2800 2900) $PN U60
J 2
(-2810 2910);
DISPLAY 0.617021 (-2810 2910);
PAINT ORANGE (-2810 2910);
FORCEPROP 2 LASTPIN (-2800 2850) $PN U58
J 2
(-2810 2860);
DISPLAY 0.617021 (-2810 2860);
PAINT ORANGE (-2810 2860);
FORCEPROP 2 LASTPIN (-2800 2800) $PN U56
J 2
(-2810 2810);
DISPLAY 0.617021 (-2810 2810);
PAINT ORANGE (-2810 2810);
FORCEPROP 2 LASTPIN (-2800 2750) $PN U54
J 2
(-2810 2760);
DISPLAY 0.617021 (-2810 2760);
PAINT ORANGE (-2810 2760);
FORCEPROP 2 LASTPIN (-2800 2700) $PN U52
J 2
(-2810 2710);
DISPLAY 0.617021 (-2810 2710);
PAINT ORANGE (-2810 2710);
FORCEPROP 2 LASTPIN (-2800 2650) $PN U50
J 2
(-2810 2660);
DISPLAY 0.617021 (-2810 2660);
PAINT ORANGE (-2810 2660);
FORCEPROP 2 LASTPIN (-2800 2600) $PN U48
J 2
(-2810 2610);
DISPLAY 0.617021 (-2810 2610);
PAINT ORANGE (-2810 2610);
FORCEPROP 2 LASTPIN (-2800 2550) $PN U46
J 2
(-2810 2560);
DISPLAY 0.617021 (-2810 2560);
PAINT ORANGE (-2810 2560);
FORCEPROP 2 LASTPIN (-2800 2500) $PN N64
J 2
(-2810 2510);
DISPLAY 0.617021 (-2810 2510);
PAINT ORANGE (-2810 2510);
FORCEPROP 2 LASTPIN (-2800 2450) $PN L62
J 2
(-2810 2460);
DISPLAY 0.617021 (-2810 2460);
PAINT ORANGE (-2810 2460);
FORCEPROP 2 LASTPIN (-2800 2400) $PN L60
J 2
(-2810 2410);
DISPLAY 0.617021 (-2810 2410);
PAINT ORANGE (-2810 2410);
FORCEPROP 2 LASTPIN (-2800 2350) $PN L58
J 2
(-2810 2360);
DISPLAY 0.617021 (-2810 2360);
PAINT ORANGE (-2810 2360);
FORCEPROP 2 LASTPIN (-2800 2300) $PN L56
J 2
(-2810 2310);
DISPLAY 0.617021 (-2810 2310);
PAINT ORANGE (-2810 2310);
FORCEPROP 2 LASTPIN (-2800 2250) $PN L54
J 2
(-2810 2260);
DISPLAY 0.617021 (-2810 2260);
PAINT ORANGE (-2810 2260);
FORCEPROP 2 LASTPIN (-2800 2200) $PN L52
J 2
(-2810 2210);
DISPLAY 0.617021 (-2810 2210);
PAINT ORANGE (-2810 2210);
FORCEPROP 2 LASTPIN (-2800 2150) $PN L50
J 2
(-2810 2160);
DISPLAY 0.617021 (-2810 2160);
PAINT ORANGE (-2810 2160);
FORCEPROP 2 LASTPIN (-2800 2100) $PN L48
J 2
(-2810 2110);
DISPLAY 0.617021 (-2810 2110);
PAINT ORANGE (-2810 2110);
FORCEPROP 2 LASTPIN (-2800 2050) $PN L46
J 2
(-2810 2060);
DISPLAY 0.617021 (-2810 2060);
PAINT ORANGE (-2810 2060);
FORCEPROP 2 LASTPIN (-2800 2000) $PN E64
J 2
(-2810 2010);
DISPLAY 0.617021 (-2810 2010);
PAINT ORANGE (-2810 2010);
FORCEPROP 2 LASTPIN (-2800 1950) $PN E62
J 2
(-2810 1960);
DISPLAY 0.617021 (-2810 1960);
PAINT ORANGE (-2810 1960);
FORCEPROP 2 LASTPIN (-2800 1900) $PN E60
J 2
(-2810 1910);
DISPLAY 0.617021 (-2810 1910);
PAINT ORANGE (-2810 1910);
FORCEPROP 2 LASTPIN (-2800 1850) $PN E58
J 2
(-2810 1860);
DISPLAY 0.617021 (-2810 1860);
PAINT ORANGE (-2810 1860);
FORCEPROP 2 LASTPIN (-2800 1800) $PN E56
J 2
(-2810 1810);
DISPLAY 0.617021 (-2810 1810);
PAINT ORANGE (-2810 1810);
FORCEPROP 2 LASTPIN (-2800 1750) $PN E54
J 2
(-2810 1760);
DISPLAY 0.617021 (-2810 1760);
PAINT ORANGE (-2810 1760);
FORCEPROP 2 LASTPIN (-2800 1700) $PN E52
J 2
(-2810 1710);
DISPLAY 0.617021 (-2810 1710);
PAINT ORANGE (-2810 1710);
FORCEPROP 2 LASTPIN (-2800 1650) $PN E50
J 2
(-2810 1660);
DISPLAY 0.617021 (-2810 1660);
PAINT ORANGE (-2810 1660);
FORCEPROP 2 LASTPIN (-2800 1600) $PN E48
J 2
(-2810 1610);
DISPLAY 0.617021 (-2810 1610);
PAINT ORANGE (-2810 1610);
FORCEPROP 2 LASTPIN (-2800 1550) $PN E46
J 2
(-2810 1560);
DISPLAY 0.617021 (-2810 1560);
PAINT ORANGE (-2810 1560);
FORCEPROP 2 LASTPIN (-2800 1450) $PN B59
J 2
(-2810 1460);
DISPLAY 0.617021 (-2810 1460);
PAINT ORANGE (-2810 1460);
FORCEPROP 2 LASTPIN (-2800 1400) $PN B53
J 2
(-2810 1410);
DISPLAY 0.617021 (-2810 1410);
PAINT ORANGE (-2810 1410);
FORCEPROP 2 LASTPIN (-2800 1350) $PN B49
J 2
(-2810 1360);
DISPLAY 0.617021 (-2810 1360);
PAINT ORANGE (-2810 1360);
FORCEPROP 2 LASTPIN (-1100 3100) $PN DH61
J 0
(-1090 3110);
DISPLAY 0.617021 (-1090 3110);
PAINT ORANGE (-1090 3110);
FORCEPROP 1 LAST LOCATION U5D1
J 0
(-2750 4200);
DISPLAY 0.617021 (-2750 4200);
PAINT AQUA (-2750 4200);
FORCEPROP 2 LASTPIN (-1100 1450) $PN EF53
J 0
(-1090 1460);
DISPLAY 0.617021 (-1090 1460);
PAINT ORANGE (-1090 1460);
FORCEPROP 2 LASTPIN (-1100 3050) $PN DH63
J 0
(-1090 3060);
DISPLAY 0.617021 (-1090 3060);
PAINT ORANGE (-1090 3060);
FORCEPROP 1 LAST PACK_TYPE BGA1
J 0
(-2750 4250);
PAINT SKYBLUE (-2750 4250);
DISPLAY INVISIBLE (-2750 4250);
FORCEPROP 2 LAST SEC_TYPE BGA1
J 0
(-2750 4250);
DISPLAY 1.021277 (-2750 4250);
PAINT ORANGE (-2750 4250);
DISPLAY INVISIBLE (-2750 4250);
FORCEPROP 2 LAST CDS_LIB chpset_lib
J 0
(-1950 2650);
PAINT ORANGE (-1950 2650);
DISPLAY INVISIBLE (-1950 2650);
FORCEPROP 2 LAST SEC 20
J 0
(-2750 4250);
DISPLAY 0.680851 (-2750 4250);
PAINT MONO (-2750 4250);
DISPLAY INVISIBLE (-2750 4250);
FORCEPROP 2 LAST CDS_LOCATION U5D1
J 0
(-2750 4200);
DISPLAY 0.617021 (-2750 4200);
PAINT AQUA (-2750 4200);
DISPLAY INVISIBLE (-2750 4200);
FORCEPROP 1 LAST PATH I33
J 0
(-1950 4150);
PAINT GREEN (-1950 4150);
DISPLAY INVISIBLE (-1950 4150);
FORCEPROP 0 LAST ROOM CPU0
J 0
(-2750 4300);
DISPLAY 1.021277 (-2750 4300);
PAINT ORANGE (-2750 4300);
DISPLAY INVISIBLE (-2750 4300);
FORCEADD SKX_EXT_B..21
(1050 2725);
FORCEPROP 2 LASTPIN (1950 2425) $PN BP15
J 0
(1960 2435);
DISPLAY 0.617021 (1960 2435);
PAINT ORANGE (1960 2435);
FORCEPROP 1 LAST LOCATION U5D1
J 0
(200 4975);
DISPLAY 0.617021 (200 4975);
PAINT AQUA (200 4975);
FORCEPROP 1 LAST PART_NUMBER TBD
J 0
(200 475);
DISPLAY 0.617021 (200 475);
PAINT BLUE (200 475);
FORCEPROP 1 LAST MATERIAL IC
J 0
(200 4925);
DISPLAY 0.617021 (200 4925);
PAINT SKYBLUE (200 4925);
FORCEPROP 2 LASTPIN (1950 4725) $PN CB65
J 0
(1960 4735);
DISPLAY 0.617021 (1960 4735);
PAINT ORANGE (1960 4735);
FORCEPROP 2 LASTPIN (1950 4675) $PN CB67
J 0
(1960 4685);
DISPLAY 0.617021 (1960 4685);
PAINT ORANGE (1960 4685);
FORCEPROP 2 LASTPIN (1950 4625) $PN CB69
J 0
(1960 4635);
DISPLAY 0.617021 (1960 4635);
PAINT ORANGE (1960 4635);
FORCEPROP 2 LASTPIN (1950 4575) $PN CC66
J 0
(1960 4585);
DISPLAY 0.617021 (1960 4585);
PAINT ORANGE (1960 4585);
FORCEPROP 2 LASTPIN (1950 4525) $PN CC68
J 0
(1960 4535);
DISPLAY 0.617021 (1960 4535);
PAINT ORANGE (1960 4535);
FORCEPROP 2 LASTPIN (1950 4475) $PN CC70
J 0
(1960 4485);
DISPLAY 0.617021 (1960 4485);
PAINT ORANGE (1960 4485);
FORCEPROP 2 LASTPIN (1950 4425) $PN CD65
J 0
(1960 4435);
DISPLAY 0.617021 (1960 4435);
PAINT ORANGE (1960 4435);
FORCEPROP 2 LASTPIN (1950 4375) $PN CD67
J 0
(1960 4385);
DISPLAY 0.617021 (1960 4385);
PAINT ORANGE (1960 4385);
FORCEPROP 2 LASTPIN (1950 4325) $PN CD69
J 0
(1960 4335);
DISPLAY 0.617021 (1960 4335);
PAINT ORANGE (1960 4335);
FORCEPROP 2 LASTPIN (1950 4275) $PN CD71
J 0
(1960 4285);
DISPLAY 0.617021 (1960 4285);
PAINT ORANGE (1960 4285);
FORCEPROP 2 LASTPIN (1950 4225) $PN CE64
J 0
(1960 4235);
DISPLAY 0.617021 (1960 4235);
PAINT ORANGE (1960 4235);
FORCEPROP 2 LASTPIN (1950 4175) $PN CE66
J 0
(1960 4185);
DISPLAY 0.617021 (1960 4185);
PAINT ORANGE (1960 4185);
FORCEPROP 2 LASTPIN (1950 4125) $PN CE68
J 0
(1960 4135);
DISPLAY 0.617021 (1960 4135);
PAINT ORANGE (1960 4135);
FORCEPROP 2 LASTPIN (1950 4075) $PN CE72
J 0
(1960 4085);
DISPLAY 0.617021 (1960 4085);
PAINT ORANGE (1960 4085);
FORCEPROP 2 LASTPIN (1950 4025) $PN CE74
J 0
(1960 4035);
DISPLAY 0.617021 (1960 4035);
PAINT ORANGE (1960 4035);
FORCEPROP 2 LASTPIN (1950 3975) $PN CF65
J 0
(1960 3985);
DISPLAY 0.617021 (1960 3985);
PAINT ORANGE (1960 3985);
FORCEPROP 2 LASTPIN (1950 3925) $PN CF67
J 0
(1960 3935);
DISPLAY 0.617021 (1960 3935);
PAINT ORANGE (1960 3935);
FORCEPROP 2 LASTPIN (1950 3875) $PN CF73
J 0
(1960 3885);
DISPLAY 0.617021 (1960 3885);
PAINT ORANGE (1960 3885);
FORCEPROP 2 LASTPIN (1950 3825) $PN CF75
J 0
(1960 3835);
DISPLAY 0.617021 (1960 3835);
PAINT ORANGE (1960 3835);
FORCEPROP 2 LASTPIN (1950 3775) $PN CG64
J 0
(1960 3785);
DISPLAY 0.617021 (1960 3785);
PAINT ORANGE (1960 3785);
FORCEPROP 2 LASTPIN (1950 3725) $PN CG66
J 0
(1960 3735);
DISPLAY 0.617021 (1960 3735);
PAINT ORANGE (1960 3735);
FORCEPROP 2 LASTPIN (1950 3675) $PN CG74
J 0
(1960 3685);
DISPLAY 0.617021 (1960 3685);
PAINT ORANGE (1960 3685);
FORCEPROP 2 LASTPIN (1950 3625) $PN CH65
J 0
(1960 3635);
DISPLAY 0.617021 (1960 3635);
PAINT ORANGE (1960 3635);
FORCEPROP 2 LASTPIN (1950 3575) $PN CH75
J 0
(1960 3585);
DISPLAY 0.617021 (1960 3585);
PAINT ORANGE (1960 3585);
FORCEPROP 2 LASTPIN (1950 3525) $PN CJ64
J 0
(1960 3535);
DISPLAY 0.617021 (1960 3535);
PAINT ORANGE (1960 3535);
FORCEPROP 2 LASTPIN (1950 3475) $PN CJ66
J 0
(1960 3485);
DISPLAY 0.617021 (1960 3485);
PAINT ORANGE (1960 3485);
FORCEPROP 2 LASTPIN (150 4725) $PN AR28
J 2
(140 4735);
DISPLAY 0.617021 (140 4735);
PAINT ORANGE (140 4735);
FORCEPROP 2 LASTPIN (150 4675) $PN AL28
J 2
(140 4685);
DISPLAY 0.617021 (140 4685);
PAINT ORANGE (140 4685);
FORCEPROP 2 LASTPIN (150 4625) $PN AM29
J 2
(140 4635);
DISPLAY 0.617021 (140 4635);
PAINT ORANGE (140 4635);
FORCEPROP 2 LASTPIN (150 4575) $PN AG34
J 2
(140 4585);
DISPLAY 0.617021 (140 4585);
PAINT ORANGE (140 4585);
FORCEPROP 2 LASTPIN (150 4525) $PN AE34
J 2
(140 4535);
DISPLAY 0.617021 (140 4535);
PAINT ORANGE (140 4535);
FORCEPROP 2 LASTPIN (150 4475) $PN AD35
J 2
(140 4485);
DISPLAY 0.617021 (140 4485);
PAINT ORANGE (140 4485);
FORCEPROP 2 LASTPIN (150 4425) $PN AF35
J 2
(140 4435);
DISPLAY 0.617021 (140 4435);
PAINT ORANGE (140 4435);
FORCEPROP 2 LASTPIN (150 4325) $PN AD37
J 2
(140 4335);
DISPLAY 0.617021 (140 4335);
PAINT ORANGE (140 4335);
FORCEPROP 2 LASTPIN (150 4275) $PN AE36
J 2
(140 4285);
DISPLAY 0.617021 (140 4285);
PAINT ORANGE (140 4285);
FORCEPROP 2 LASTPIN (150 4225) $PN BF27
J 2
(140 4235);
DISPLAY 0.617021 (140 4235);
PAINT ORANGE (140 4235);
FORCEPROP 2 LASTPIN (150 4175) $PN BG26
J 2
(140 4185);
DISPLAY 0.617021 (140 4185);
PAINT ORANGE (140 4185);
FORCEPROP 2 LASTPIN (150 4125) $PN BH25
J 2
(140 4135);
DISPLAY 0.617021 (140 4135);
PAINT ORANGE (140 4135);
FORCEPROP 2 LASTPIN (150 4075) $PN BH27
J 2
(140 4085);
DISPLAY 0.617021 (140 4085);
PAINT ORANGE (140 4085);
FORCEPROP 2 LASTPIN (150 4025) $PN BJ26
J 2
(140 4035);
DISPLAY 0.617021 (140 4035);
PAINT ORANGE (140 4035);
FORCEPROP 2 LASTPIN (150 3975) $PN BK25
J 2
(140 3985);
DISPLAY 0.617021 (140 3985);
PAINT ORANGE (140 3985);
FORCEPROP 2 LASTPIN (150 3925) $PN BK27
J 2
(140 3935);
DISPLAY 0.617021 (140 3935);
PAINT ORANGE (140 3935);
FORCEPROP 2 LASTPIN (150 3875) $PN BL26
J 2
(140 3885);
DISPLAY 0.617021 (140 3885);
PAINT ORANGE (140 3885);
FORCEPROP 2 LASTPIN (150 3825) $PN BM27
J 2
(140 3835);
DISPLAY 0.617021 (140 3835);
PAINT ORANGE (140 3835);
FORCEPROP 2 LASTPIN (150 3775) $PN CH27
J 2
(140 3785);
DISPLAY 0.617021 (140 3785);
PAINT ORANGE (140 3785);
FORCEPROP 2 LASTPIN (150 3725) $PN CJ28
J 2
(140 3735);
DISPLAY 0.617021 (140 3735);
PAINT ORANGE (140 3735);
FORCEPROP 2 LASTPIN (150 3625) $PN CD27
J 2
(140 3635);
DISPLAY 0.617021 (140 3635);
PAINT ORANGE (140 3635);
FORCEPROP 2 LASTPIN (150 3575) $PN CF27
J 2
(140 3585);
DISPLAY 0.617021 (140 3585);
PAINT ORANGE (140 3585);
FORCEPROP 2 LASTPIN (150 3525) $PN AV27
J 2
(140 3535);
DISPLAY 0.617021 (140 3535);
PAINT ORANGE (140 3535);
FORCEPROP 2 LASTPIN (150 3475) $PN AW26
J 2
(140 3485);
DISPLAY 0.617021 (140 3485);
PAINT ORANGE (140 3485);
FORCEPROP 2 LASTPIN (150 3425) $PN AY27
J 2
(140 3435);
DISPLAY 0.617021 (140 3435);
PAINT ORANGE (140 3435);
FORCEPROP 2 LASTPIN (150 3375) $PN BA26
J 2
(140 3385);
DISPLAY 0.617021 (140 3385);
PAINT ORANGE (140 3385);
FORCEPROP 2 LASTPIN (150 3325) $PN BB27
J 2
(140 3335);
DISPLAY 0.617021 (140 3335);
PAINT ORANGE (140 3335);
FORCEPROP 2 LASTPIN (150 3275) $PN BC26
J 2
(140 3285);
DISPLAY 0.617021 (140 3285);
PAINT ORANGE (140 3285);
FORCEPROP 2 LASTPIN (150 3225) $PN W10
J 2
(140 3235);
DISPLAY 0.617021 (140 3235);
PAINT ORANGE (140 3235);
FORCEPROP 2 LASTPIN (150 3175) $PN N18
J 2
(140 3185);
DISPLAY 0.617021 (140 3185);
PAINT ORANGE (140 3185);
FORCEPROP 2 LASTPIN (150 3125) $PN M9
J 2
(140 3135);
DISPLAY 0.617021 (140 3135);
PAINT ORANGE (140 3135);
FORCEPROP 2 LASTPIN (150 3075) $PN M7
J 2
(140 3085);
DISPLAY 0.617021 (140 3085);
PAINT ORANGE (140 3085);
FORCEPROP 2 LASTPIN (150 3025) $PN K15
J 2
(140 3035);
DISPLAY 0.617021 (140 3035);
PAINT ORANGE (140 3035);
FORCEPROP 2 LASTPIN (150 2975) $PN J2
J 2
(140 2985);
DISPLAY 0.617021 (140 2985);
PAINT ORANGE (140 2985);
FORCEPROP 2 LASTPIN (150 2925) $PN EB15
J 2
(140 2935);
DISPLAY 0.617021 (140 2935);
PAINT ORANGE (140 2935);
FORCEPROP 2 LASTPIN (150 2875) $PN EA12
J 2
(140 2885);
DISPLAY 0.617021 (140 2885);
PAINT ORANGE (140 2885);
FORCEPROP 2 LASTPIN (150 2825) $PN DU20
J 2
(140 2835);
DISPLAY 0.617021 (140 2835);
PAINT ORANGE (140 2835);
FORCEPROP 2 LASTPIN (150 2775) $PN DR2
J 2
(140 2785);
DISPLAY 0.617021 (140 2785);
PAINT ORANGE (140 2785);
FORCEPROP 2 LASTPIN (150 2725) $PN DR10
J 2
(140 2735);
DISPLAY 0.617021 (140 2735);
PAINT ORANGE (140 2735);
FORCEPROP 2 LASTPIN (150 2675) $PN DP19
J 2
(140 2685);
DISPLAY 0.617021 (140 2685);
PAINT ORANGE (140 2685);
FORCEPROP 2 LASTPIN (150 2625) $PN DN8
J 2
(140 2635);
DISPLAY 0.617021 (140 2635);
PAINT ORANGE (140 2635);
FORCEPROP 2 LASTPIN (150 2575) $PN DM17
J 2
(140 2585);
DISPLAY 0.617021 (140 2585);
PAINT ORANGE (140 2585);
FORCEPROP 2 LASTPIN (150 2525) $PN DJ16
J 2
(140 2535);
DISPLAY 0.617021 (140 2535);
PAINT ORANGE (140 2535);
FORCEPROP 2 LASTPIN (150 2475) $PN H13
J 2
(140 2485);
DISPLAY 0.617021 (140 2485);
PAINT ORANGE (140 2485);
FORCEPROP 2 LASTPIN (150 2425) $PN J10
J 2
(140 2435);
DISPLAY 0.617021 (140 2435);
PAINT ORANGE (140 2435);
FORCEPROP 2 LASTPIN (150 2375) $PN L14
J 2
(140 2385);
DISPLAY 0.617021 (140 2385);
PAINT ORANGE (140 2385);
FORCEPROP 2 LASTPIN (150 2325) $PN L16
J 2
(140 2335);
DISPLAY 0.617021 (140 2335);
PAINT ORANGE (140 2335);
FORCEPROP 2 LASTPIN (150 2275) $PN DH7
J 2
(140 2285);
DISPLAY 0.617021 (140 2285);
PAINT ORANGE (140 2285);
FORCEPROP 2 LASTPIN (150 2225) $PN DG8
J 2
(140 2235);
DISPLAY 0.617021 (140 2235);
PAINT ORANGE (140 2235);
FORCEPROP 2 LASTPIN (150 2175) $PN M11
J 2
(140 2185);
DISPLAY 0.617021 (140 2185);
PAINT ORANGE (140 2185);
FORCEPROP 2 LASTPIN (150 2075) $PN P5
J 2
(140 2085);
DISPLAY 0.617021 (140 2085);
PAINT ORANGE (140 2085);
FORCEPROP 2 LASTPIN (150 2025) $PN T3
J 2
(140 2035);
DISPLAY 0.617021 (140 2035);
PAINT ORANGE (140 2035);
FORCEPROP 2 LASTPIN (150 1975) $PN U14
J 2
(140 1985);
DISPLAY 0.617021 (140 1985);
PAINT ORANGE (140 1985);
FORCEPROP 2 LASTPIN (150 1925) $PN DF21
J 2
(140 1935);
DISPLAY 0.617021 (140 1935);
PAINT ORANGE (140 1935);
FORCEPROP 2 LASTPIN (150 1875) $PN W4
J 2
(140 1885);
DISPLAY 0.617021 (140 1885);
PAINT ORANGE (140 1885);
FORCEPROP 2 LASTPIN (150 1825) $PN W6
J 2
(140 1835);
DISPLAY 0.617021 (140 1835);
PAINT ORANGE (140 1835);
FORCEPROP 2 LASTPIN (150 1775) $PN AA10
J 2
(140 1785);
DISPLAY 0.617021 (140 1785);
PAINT ORANGE (140 1785);
FORCEPROP 2 LASTPIN (150 1725) $PN AC20
J 2
(140 1735);
DISPLAY 0.617021 (140 1735);
PAINT ORANGE (140 1735);
FORCEPROP 2 LASTPIN (150 1675) $PN AC4
J 2
(140 1685);
DISPLAY 0.617021 (140 1685);
PAINT ORANGE (140 1685);
FORCEPROP 2 LASTPIN (150 1625) $PN AH9
J 2
(140 1635);
DISPLAY 0.617021 (140 1635);
PAINT ORANGE (140 1635);
FORCEPROP 2 LASTPIN (150 1575) $PN DF13
J 2
(140 1585);
DISPLAY 0.617021 (140 1585);
PAINT ORANGE (140 1585);
FORCEPROP 2 LASTPIN (150 1525) $PN AN10
J 2
(140 1535);
DISPLAY 0.617021 (140 1535);
PAINT ORANGE (140 1535);
FORCEPROP 2 LASTPIN (150 1475) $PN DD7
J 2
(140 1485);
DISPLAY 0.617021 (140 1485);
PAINT ORANGE (140 1485);
FORCEPROP 2 LASTPIN (150 1425) $PN AT11
J 2
(140 1435);
DISPLAY 0.617021 (140 1435);
PAINT ORANGE (140 1435);
FORCEPROP 2 LASTPIN (150 1375) $PN AW6
J 2
(140 1385);
DISPLAY 0.617021 (140 1385);
PAINT ORANGE (140 1385);
FORCEPROP 2 LASTPIN (150 1325) $PN AY11
J 2
(140 1335);
DISPLAY 0.617021 (140 1335);
PAINT ORANGE (140 1335);
FORCEPROP 2 LASTPIN (150 1225) $PN BB5
J 2
(140 1235);
DISPLAY 0.617021 (140 1235);
PAINT ORANGE (140 1235);
FORCEPROP 2 LASTPIN (150 1175) $PN DA14
J 2
(140 1185);
DISPLAY 0.617021 (140 1185);
PAINT ORANGE (140 1185);
FORCEPROP 2 LASTPIN (150 1125) $PN BF23
J 2
(140 1135);
DISPLAY 0.617021 (140 1135);
PAINT ORANGE (140 1135);
FORCEPROP 2 LASTPIN (150 1075) $PN BJ24
J 2
(140 1085);
DISPLAY 0.617021 (140 1085);
PAINT ORANGE (140 1085);
FORCEPROP 2 LASTPIN (150 1025) $PN BP25
J 2
(140 1035);
DISPLAY 0.617021 (140 1035);
PAINT ORANGE (140 1035);
FORCEPROP 2 LASTPIN (1950 1175) $PN CB13
J 0
(1960 1185);
DISPLAY 0.617021 (1960 1185);
PAINT ORANGE (1960 1185);
FORCEPROP 2 LASTPIN (1950 1125) $PN CB17
J 0
(1960 1135);
DISPLAY 0.617021 (1960 1135);
PAINT ORANGE (1960 1135);
FORCEPROP 2 LASTPIN (1950 1075) $PN CD9
J 0
(1960 1085);
DISPLAY 0.617021 (1960 1085);
PAINT ORANGE (1960 1085);
FORCEPROP 2 LASTPIN (1950 1025) $PN CE18
J 0
(1960 1035);
DISPLAY 0.617021 (1960 1035);
PAINT ORANGE (1960 1035);
FORCEPROP 2 LASTPIN (1950 975) $PN D7
J 0
(1960 985);
DISPLAY 0.617021 (1960 985);
PAINT ORANGE (1960 985);
FORCEPROP 2 LASTPIN (1950 925) $PN CH9
J 0
(1960 935);
DISPLAY 0.617021 (1960 935);
PAINT ORANGE (1960 935);
FORCEPROP 2 LASTPIN (1950 825) $PN CV7
J 0
(1960 835);
DISPLAY 0.617021 (1960 835);
PAINT ORANGE (1960 835);
FORCEPROP 2 LASTPIN (1950 775) $PN CK5
J 0
(1960 785);
DISPLAY 0.617021 (1960 785);
PAINT ORANGE (1960 785);
FORCEPROP 2 LASTPIN (1950 725) $PN CL12
J 0
(1960 735);
DISPLAY 0.617021 (1960 735);
PAINT ORANGE (1960 735);
FORCEPROP 2 LASTPIN (1950 675) $PN CM15
J 0
(1960 685);
DISPLAY 0.617021 (1960 685);
PAINT ORANGE (1960 685);
FORCEPROP 2 LASTPIN (1950 1275) $PN CY55
J 0
(1960 1285);
DISPLAY 0.617021 (1960 1285);
PAINT ORANGE (1960 1285);
FORCEPROP 2 LASTPIN (1950 1775) $PN A8
J 0
(1960 1785);
DISPLAY 0.617021 (1960 1785);
PAINT ORANGE (1960 1785);
FORCEPROP 2 LASTPIN (1950 1725) $PN A10
J 0
(1960 1735);
DISPLAY 0.617021 (1960 1735);
PAINT ORANGE (1960 1735);
FORCEPROP 2 LASTPIN (1950 1625) $PN B11
J 0
(1960 1635);
DISPLAY 0.617021 (1960 1635);
PAINT ORANGE (1960 1635);
FORCEPROP 2 LASTPIN (1950 2675) $PN BM11
J 0
(1960 2685);
DISPLAY 0.617021 (1960 2685);
PAINT ORANGE (1960 2685);
FORCEPROP 2 LASTPIN (1950 2625) $PN BN12
J 0
(1960 2635);
DISPLAY 0.617021 (1960 2635);
PAINT ORANGE (1960 2635);
FORCEPROP 2 LASTPIN (1950 2575) $PN BN14
J 0
(1960 2585);
DISPLAY 0.617021 (1960 2585);
PAINT ORANGE (1960 2585);
FORCEPROP 2 LASTPIN (1950 2525) $PN BP11
J 0
(1960 2535);
DISPLAY 0.617021 (1960 2535);
PAINT ORANGE (1960 2535);
FORCEPROP 2 LASTPIN (1950 2475) $PN BP13
J 0
(1960 2485);
DISPLAY 0.617021 (1960 2485);
PAINT ORANGE (1960 2485);
FORCEPROP 2 LASTPIN (1950 2325) $PN BR12
J 0
(1960 2335);
DISPLAY 0.617021 (1960 2335);
PAINT ORANGE (1960 2335);
FORCEPROP 2 LASTPIN (1950 2275) $PN BR14
J 0
(1960 2285);
DISPLAY 0.617021 (1960 2285);
PAINT ORANGE (1960 2285);
FORCEPROP 2 LASTPIN (1950 2225) $PN BT11
J 0
(1960 2235);
DISPLAY 0.617021 (1960 2235);
PAINT ORANGE (1960 2235);
FORCEPROP 2 LASTPIN (1950 2175) $PN BT13
J 0
(1960 2185);
DISPLAY 0.617021 (1960 2185);
PAINT ORANGE (1960 2185);
FORCEPROP 2 LASTPIN (1950 2125) $PN BT15
J 0
(1960 2135);
DISPLAY 0.617021 (1960 2135);
PAINT ORANGE (1960 2135);
FORCEPROP 2 LASTPIN (1950 2075) $PN BU12
J 0
(1960 2085);
DISPLAY 0.617021 (1960 2085);
PAINT ORANGE (1960 2085);
FORCEPROP 2 LASTPIN (1950 2025) $PN BU14
J 0
(1960 2035);
DISPLAY 0.617021 (1960 2035);
PAINT ORANGE (1960 2035);
FORCEPROP 2 LASTPIN (1950 1975) $PN BV11
J 0
(1960 1985);
DISPLAY 0.617021 (1960 1985);
PAINT ORANGE (1960 1985);
FORCEPROP 2 LASTPIN (1950 1925) $PN BV13
J 0
(1960 1935);
DISPLAY 0.617021 (1960 1935);
PAINT ORANGE (1960 1935);
FORCEPROP 2 LASTPIN (1950 1875) $PN BV15
J 0
(1960 1885);
DISPLAY 0.617021 (1960 1885);
PAINT ORANGE (1960 1885);
FORCEPROP 2 LASTPIN (1950 1525) $PN BY27
J 0
(1960 1535);
DISPLAY 0.617021 (1960 1535);
PAINT ORANGE (1960 1535);
FORCEPROP 2 LASTPIN (1950 1475) $PN BV27
J 0
(1960 1485);
DISPLAY 0.617021 (1960 1485);
PAINT ORANGE (1960 1485);
FORCEPROP 2 LASTPIN (1950 1425) $PN BU26
J 0
(1960 1435);
DISPLAY 0.617021 (1960 1435);
PAINT ORANGE (1960 1435);
FORCEPROP 2 LASTPIN (1950 1375) $PN BT27
J 0
(1960 1385);
DISPLAY 0.617021 (1960 1385);
PAINT ORANGE (1960 1385);
FORCEPROP 2 LASTPIN (1950 3375) $PN BD13
J 0
(1960 3385);
DISPLAY 0.617021 (1960 3385);
PAINT ORANGE (1960 3385);
FORCEPROP 2 LASTPIN (1950 3325) $PN BE12
J 0
(1960 3335);
DISPLAY 0.617021 (1960 3335);
PAINT ORANGE (1960 3335);
FORCEPROP 2 LASTPIN (1950 3275) $PN BE14
J 0
(1960 3285);
DISPLAY 0.617021 (1960 3285);
PAINT ORANGE (1960 3285);
FORCEPROP 2 LASTPIN (1950 3225) $PN BF11
J 0
(1960 3235);
DISPLAY 0.617021 (1960 3235);
PAINT ORANGE (1960 3235);
FORCEPROP 2 LASTPIN (1950 3175) $PN BF13
J 0
(1960 3185);
DISPLAY 0.617021 (1960 3185);
PAINT ORANGE (1960 3185);
FORCEPROP 2 LASTPIN (1950 3125) $PN BG12
J 0
(1960 3135);
DISPLAY 0.617021 (1960 3135);
PAINT ORANGE (1960 3135);
FORCEPROP 2 LASTPIN (1950 3075) $PN BG14
J 0
(1960 3085);
DISPLAY 0.617021 (1960 3085);
PAINT ORANGE (1960 3085);
FORCEPROP 2 LASTPIN (1950 3025) $PN BH13
J 0
(1960 3035);
DISPLAY 0.617021 (1960 3035);
PAINT ORANGE (1960 3035);
FORCEPROP 2 LASTPIN (1950 2975) $PN BJ12
J 0
(1960 2985);
DISPLAY 0.617021 (1960 2985);
PAINT ORANGE (1960 2985);
FORCEPROP 2 LASTPIN (1950 2925) $PN BJ14
J 0
(1960 2935);
DISPLAY 0.617021 (1960 2935);
PAINT ORANGE (1960 2935);
FORCEPROP 2 LASTPIN (1950 2875) $PN BK13
J 0
(1960 2885);
DISPLAY 0.617021 (1960 2885);
PAINT ORANGE (1960 2885);
FORCEPROP 2 LASTPIN (1950 2825) $PN BK15
J 0
(1960 2835);
DISPLAY 0.617021 (1960 2835);
PAINT ORANGE (1960 2835);
FORCEPROP 2 LASTPIN (1950 2775) $PN BL14
J 0
(1960 2785);
DISPLAY 0.617021 (1960 2785);
PAINT ORANGE (1960 2785);
FORCEPROP 2 LASTPIN (150 1275) $PN BA24
J 2
(140 1285);
DISPLAY 0.617021 (140 1285);
PAINT ORANGE (140 1285);
FORCEPROP 2 LASTPIN (150 4375) $PN AC36
J 2
(140 4385);
DISPLAY 0.617021 (140 4385);
PAINT ORANGE (140 4385);
FORCEPROP 2 LASTPIN (1950 1675) $PN A12
J 0
(1960 1685);
DISPLAY 0.617021 (1960 1685);
PAINT ORANGE (1960 1685);
FORCEPROP 2 LASTPIN (150 2125) $PN M21
J 2
(140 2135);
DISPLAY 0.617021 (140 2135);
PAINT ORANGE (140 2135);
FORCEPROP 2 LASTPIN (150 3675) $PN CC26
J 2
(140 3685);
DISPLAY 0.617021 (140 3685);
PAINT ORANGE (140 3685);
FORCEPROP 1 LAST PACK_TYPE BGA1
J 0
(200 5025);
PAINT SKYBLUE (200 5025);
DISPLAY INVISIBLE (200 5025);
FORCEPROP 2 LAST SEC_TYPE BGA1
J 0
(200 5025);
DISPLAY 1.021277 (200 5025);
PAINT ORANGE (200 5025);
DISPLAY INVISIBLE (200 5025);
FORCEPROP 2 LAST CDS_LIB chpset_lib
J 0
(1050 2725);
PAINT ORANGE (1050 2725);
DISPLAY INVISIBLE (1050 2725);
FORCEPROP 2 LAST SEC 21
J 0
(200 5025);
DISPLAY 0.680851 (200 5025);
PAINT MONO (200 5025);
DISPLAY INVISIBLE (200 5025);
FORCEPROP 2 LAST CDS_LOCATION U5D1
J 0
(200 4975);
DISPLAY 0.617021 (200 4975);
PAINT AQUA (200 4975);
DISPLAY INVISIBLE (200 4975);
FORCEPROP 1 LAST PATH I34
J 0
(1050 4925);
PAINT GREEN (1050 4925);
DISPLAY INVISIBLE (1050 4925);
FORCEPROP 0 LAST ROOM CPU0
J 0
(200 5075);
DISPLAY 1.021277 (200 5075);
PAINT ORANGE (200 5075);
DISPLAY INVISIBLE (200 5075);
FORCEADD VCC_CORE..1
(3000 1600);
FORCEPROP 3 LASTPIN (3000 1550) SIG_NAME P1V8_MCP_CPU0\g
J 0
(3010 1560);
DISPLAY 0.659574 (3010 1560);
PAINT MONO (3010 1560);
DISPLAY INVISIBLE (3010 1560);
FORCEPROP 1 LAST HDL_POWER P1V8_MCP_CPU0
J 1
(3000 1650);
DISPLAY 0.617021 (3000 1650);
PAINT GREEN (3000 1650);
FORCEPROP 1 LAST PATH I35
J 0
(3050 1625);
DISPLAY 0.872340 (3050 1625);
PAINT AQUA (3050 1625);
DISPLAY INVISIBLE (3050 1625);
FORCEPROP 2 LAST CDS_LIB mstr_symbols
J 0
(3000 1600);
PAINT ORANGE (3000 1600);
DISPLAY INVISIBLE (3000 1600);
FORCEPROP 0 LAST VOLTAGE +1.8V
J 0
(3000 1750);
DISPLAY 1.021277 (3000 1750);
PAINT SKYBLUE (3000 1750);
DISPLAY INVISIBLE (3000 1750);
FORCEADD P3V3_STBY..1
(2450 1375);
FORCEPROP 3 LASTPIN (2450 1325) SIG_NAME P3V3_STBY\g
J 0
(2460 1335);
DISPLAY 0.659574 (2460 1335);
PAINT MONO (2460 1335);
DISPLAY INVISIBLE (2460 1335);
FORCEPROP 1 LAST HDL_POWER P3V3_STBY
J 0
(2150 1250);
DISPLAY 0.872340 (2150 1250);
PAINT ORANGE (2150 1250);
DISPLAY INVISIBLE (2150 1250);
FORCEPROP 1 LAST PATH I36
J 0
(2495 1377);
DISPLAY 0.340426 (2495 1377);
PAINT GREEN (2495 1377);
DISPLAY INVISIBLE (2495 1377);
FORCEPROP 1 LAST BODY_TYPE PLUMBING
J 0
(2405 1332);
DISPLAY 0.340426 (2405 1332);
PAINT GREEN (2405 1332);
DISPLAY INVISIBLE (2405 1332);
FORCEPROP 1 LAST SIZE 1B
J 0
(2495 1397);
DISPLAY 0.340426 (2495 1397);
PAINT GREEN (2495 1397);
DISPLAY INVISIBLE (2495 1397);
FORCEPROP 2 LAST CDS_LIB mstr_symbols
J 0
(2450 1375);
PAINT ORANGE (2450 1375);
DISPLAY INVISIBLE (2450 1375);
FORCEPROP 1 LAST VOLTAGE 3.3V
J 0
(2405 1332);
DISPLAY 0.340426 (2405 1332);
PAINT SKYBLUE (2405 1332);
DISPLAY INVISIBLE (2405 1332);
FORCEADD DESIGN_NOTE..1
(-2550 950);
FORCEPROP 0 LAST L1 CPU SYMBOLS 1-30 ARE PRELIMINARY AND SUBJECT TO CHANGE
J 0
(-2750 825);
DISPLAY 1.021277 (-2750 825);
PAINT ORANGE (-2750 825);
FORCEPROP 1 LAST COMMENT_BODY TRUE
J 0
(-2525 1050);
DISPLAY 0.978723 (-2525 1050);
PAINT ORANGE (-2525 1050);
DISPLAY INVISIBLE (-2525 1050);
FORCEPROP 2 LAST CDS_LIB mstr_symbols
J 0
(-2550 950);
PAINT ORANGE (-2550 950);
DISPLAY INVISIBLE (-2550 950);
FORCEADD INTEL_CORP_BPAGE..1
(4125 150);
FORCEPROP 1 LAST CDS_CON_LAST_MODIFIED Fri Jun 16 17:48:14 2017
J 0
(2700 475);
DISPLAY 1.340426 (2700 475);
PAINT GREEN (2700 475);
DISPLAY INVISIBLE (2700 475);
FORCEPROP 1 LAST CUSTOM_TXT_CDS <CURRENT_DESIGN_SHEET> OF <TOTAL_DESIGN_SHEETS>
J 0
(3625 175);
PAINT ORANGE (3625 175);
FORCEPROP 1 LAST CUSTOM_TXT_CDS <CON_LAST_MODIFIED>
J 0
(125 250);
PAINT ORANGE (125 250);
FORCEPROP 2 LAST CUSTOM_TXT_CDS <XR_PAGE_TITLE>
J 0
(-3765 5400);
DISPLAY 0.638298 (-3765 5400);
PAINT PINK (-3765 5400);
DISPLAY INVISIBLE (-3765 5400);
FORCEPROP 1 LAST SCH_TITLE SKYLAKE - SKT0 - 18 OF 21
J 0
(-3825 200);
DISPLAY 1.212766 (-3825 200);
PAINT GREEN (-3825 200);
FORCEPROP 2 LAST CDS_LIB mstr_symbols
J 0
(4125 150);
PAINT ORANGE (4125 150);
DISPLAY INVISIBLE (4125 150);
FORCEPROP 2 LAST PAGE_BORDER TRUE
J 0
(-3765 5400);
DISPLAY 0.851064 (-3765 5400);
PAINT PINK (-3765 5400);
DISPLAY INVISIBLE (-3765 5400);
FORCEPROP 1 LAST COMMENT_BODY TRUE
J 0
(4137 162);
DISPLAY 0.638298 (4137 162);
PAINT GREEN (4137 162);
DISPLAY INVISIBLE (4137 162);
FORCEPROP 2 LAST CDS_XR_PAGE_TITLE CR-38 : @BASEBOARD_FAB2_LIB.BASEBOARD_FAB2(SCH_1):PAGE38
J 0
(-3765 5400);
DISPLAY 0.638298 (-3765 5400);
PAINT PINK (-3765 5400);
DISPLAY INVISIBLE (-3765 5400);
WIRE 16 -1 (-3075 4350)(-3075 3950);
WIRE 16 -1 (-3075 3950)(-3075 3900);
WIRE 16 -1 (-3075 3950)(-2800 3950);
WIRE 16 -1 (-3075 3900)(-3075 3850);
WIRE 16 -1 (-3075 3900)(-2800 3900);
WIRE 16 -1 (-3075 3850)(-3075 3800);
WIRE 16 -1 (-3075 3850)(-2800 3850);
WIRE 16 -1 (-3075 3800)(-3075 3750);
WIRE 16 -1 (-3075 3800)(-2800 3800);
WIRE 16 -1 (-3075 3750)(-3075 3700);
WIRE 16 -1 (-3075 3750)(-2800 3750);
WIRE 16 -1 (-3075 3700)(-3075 3650);
WIRE 16 -1 (-3075 3700)(-2800 3700);
WIRE 16 -1 (-3075 3650)(-3075 3600);
WIRE 16 -1 (-3075 3650)(-2800 3650);
WIRE 16 -1 (-3075 3600)(-3075 3550);
WIRE 16 -1 (-3075 3600)(-2800 3600);
WIRE 16 -1 (-3075 3550)(-3075 3500);
WIRE 16 -1 (-3075 3550)(-2800 3550);
WIRE 16 -1 (-3075 3500)(-3075 3450);
WIRE 16 -1 (-3075 3500)(-2800 3500);
WIRE 16 -1 (-3075 3450)(-3075 3400);
WIRE 16 -1 (-3075 3450)(-2800 3450);
WIRE 16 -1 (-3075 3400)(-3075 3350);
WIRE 16 -1 (-3075 3400)(-2800 3400);
WIRE 16 -1 (-3075 3350)(-3075 3300);
WIRE 16 -1 (-3075 3350)(-2800 3350);
WIRE 16 -1 (-3075 3300)(-3075 3250);
WIRE 16 -1 (-3075 3300)(-2800 3300);
WIRE 16 -1 (-3075 3250)(-3075 3200);
WIRE 16 -1 (-3075 3250)(-2800 3250);
WIRE 16 -1 (-3075 3200)(-3075 3150);
WIRE 16 -1 (-3075 3200)(-2800 3200);
WIRE 16 -1 (-3075 3150)(-3075 3100);
WIRE 16 -1 (-3075 3150)(-2800 3150);
WIRE 16 -1 (-3075 3100)(-3075 3050);
WIRE 16 -1 (-3075 3100)(-2800 3100);
WIRE 16 -1 (-3075 3050)(-3075 3000);
WIRE 16 -1 (-3075 3050)(-2800 3050);
WIRE 16 -1 (-3075 3000)(-3075 2950);
WIRE 16 -1 (-3075 3000)(-2800 3000);
WIRE 16 -1 (-3075 2950)(-3075 2900);
WIRE 16 -1 (-3075 2950)(-2800 2950);
WIRE 16 -1 (-3075 2900)(-3075 2850);
WIRE 16 -1 (-3075 2900)(-2800 2900);
WIRE 16 -1 (-3075 2850)(-3075 2800);
WIRE 16 -1 (-3075 2850)(-2800 2850);
WIRE 16 -1 (-3075 2800)(-3075 2750);
WIRE 16 -1 (-3075 2800)(-2800 2800);
WIRE 16 -1 (-3075 2750)(-3075 2700);
WIRE 16 -1 (-3075 2750)(-2800 2750);
WIRE 16 -1 (-3075 2700)(-3075 2650);
WIRE 16 -1 (-3075 2700)(-2800 2700);
WIRE 16 -1 (-3075 2650)(-3075 2600);
WIRE 16 -1 (-3075 2650)(-2800 2650);
WIRE 16 -1 (-3075 2600)(-3075 2550);
WIRE 16 -1 (-3075 2600)(-2800 2600);
WIRE 16 -1 (-3075 2550)(-3075 2500);
WIRE 16 -1 (-3075 2550)(-2800 2550);
WIRE 16 -1 (-3075 2500)(-3075 2450);
WIRE 16 -1 (-3075 2500)(-2800 2500);
WIRE 16 -1 (-3075 2450)(-3075 2400);
WIRE 16 -1 (-3075 2450)(-2800 2450);
WIRE 16 -1 (-3075 2400)(-3075 2350);
WIRE 16 -1 (-3075 2400)(-2800 2400);
WIRE 16 -1 (-3075 2350)(-3075 2300);
WIRE 16 -1 (-3075 2350)(-2800 2350);
WIRE 16 -1 (-3075 2300)(-3075 2250);
WIRE 16 -1 (-3075 2300)(-2800 2300);
WIRE 16 -1 (-3075 2250)(-3075 2200);
WIRE 16 -1 (-3075 2250)(-2800 2250);
WIRE 16 -1 (-3075 2200)(-3075 2150);
WIRE 16 -1 (-3075 2200)(-2800 2200);
WIRE 16 -1 (-3075 2150)(-3075 2100);
WIRE 16 -1 (-3075 2150)(-2800 2150);
WIRE 16 -1 (-3075 2100)(-3075 2050);
WIRE 16 -1 (-3075 2100)(-2800 2100);
WIRE 16 -1 (-3075 2050)(-3075 2000);
WIRE 16 -1 (-3075 2050)(-2800 2050);
WIRE 16 -1 (-3075 2000)(-3075 1950);
WIRE 16 -1 (-3075 2000)(-2800 2000);
WIRE 16 -1 (-3075 1950)(-3075 1900);
WIRE 16 -1 (-3075 1950)(-2800 1950);
WIRE 16 -1 (-3075 1900)(-3075 1850);
WIRE 16 -1 (-3075 1900)(-2800 1900);
WIRE 16 -1 (-3075 1850)(-3075 1800);
WIRE 16 -1 (-3075 1850)(-2800 1850);
WIRE 16 -1 (-3075 1800)(-3075 1750);
WIRE 16 -1 (-3075 1800)(-2800 1800);
WIRE 16 -1 (-3075 1750)(-3075 1700);
WIRE 16 -1 (-3075 1750)(-2800 1750);
WIRE 16 -1 (-3075 1700)(-3075 1650);
WIRE 16 -1 (-3075 1700)(-2800 1700);
WIRE 16 -1 (-3075 1650)(-3075 1600);
WIRE 16 -1 (-3075 1650)(-2800 1650);
WIRE 16 -1 (-3075 1600)(-3075 1550);
WIRE 16 -1 (-3075 1600)(-2800 1600);
WIRE 16 -1 (-3075 1550)(-3075 1450);
WIRE 16 -1 (-3075 1550)(-2800 1550);
WIRE 16 -1 (-3075 1450)(-3075 1400);
WIRE 16 -1 (-3075 1450)(-2800 1450);
WIRE 16 -1 (-3075 1400)(-3075 1350);
WIRE 16 -1 (-3075 1400)(-2800 1400);
WIRE 16 -1 (-3075 1350)(-2800 1350);
WIRE 16 -1 (-800 3950)(-800 4350);
WIRE 16 -1 (-800 3950)(-800 3900);
WIRE 16 -1 (-800 3950)(-1100 3950);
WIRE 16 -1 (-800 3900)(-800 3850);
WIRE 16 -1 (-800 3900)(-1100 3900);
WIRE 16 -1 (-800 3850)(-800 3800);
WIRE 16 -1 (-800 3850)(-1100 3850);
WIRE 16 -1 (-800 3800)(-800 3750);
WIRE 16 -1 (-800 3800)(-1100 3800);
WIRE 16 -1 (-800 3750)(-800 3700);
WIRE 16 -1 (-800 3750)(-1100 3750);
WIRE 16 -1 (-800 3700)(-800 3650);
WIRE 16 -1 (-800 3700)(-1100 3700);
WIRE 16 -1 (-800 3650)(-800 3600);
WIRE 16 -1 (-800 3650)(-1100 3650);
WIRE 16 -1 (-800 3600)(-800 3550);
WIRE 16 -1 (-800 3600)(-1100 3600);
WIRE 16 -1 (-800 3550)(-800 3500);
WIRE 16 -1 (-800 3550)(-1100 3550);
WIRE 16 -1 (-800 3500)(-800 3450);
WIRE 16 -1 (-800 3500)(-1100 3500);
WIRE 16 -1 (-800 3450)(-800 3400);
WIRE 16 -1 (-800 3450)(-1100 3450);
WIRE 16 -1 (-800 3400)(-800 3350);
WIRE 16 -1 (-800 3400)(-1100 3400);
WIRE 16 -1 (-800 3350)(-800 3300);
WIRE 16 -1 (-800 3350)(-1100 3350);
WIRE 16 -1 (-800 3300)(-800 3250);
WIRE 16 -1 (-800 3300)(-1100 3300);
WIRE 16 -1 (-800 3250)(-800 3200);
WIRE 16 -1 (-800 3250)(-1100 3250);
WIRE 16 -1 (-800 3200)(-800 3150);
WIRE 16 -1 (-800 3200)(-1100 3200);
WIRE 16 -1 (-800 3150)(-800 3100);
WIRE 16 -1 (-800 3150)(-1100 3150);
WIRE 16 -1 (-800 3100)(-800 3050);
WIRE 16 -1 (-800 3100)(-1100 3100);
WIRE 16 -1 (-800 3050)(-800 3000);
WIRE 16 -1 (-800 3050)(-1100 3050);
WIRE 16 -1 (-800 3000)(-800 2950);
WIRE 16 -1 (-800 3000)(-1100 3000);
WIRE 16 -1 (-800 2950)(-800 2900);
WIRE 16 -1 (-800 2950)(-1100 2950);
WIRE 16 -1 (-800 2900)(-800 2850);
WIRE 16 -1 (-800 2900)(-1100 2900);
WIRE 16 -1 (-800 2850)(-800 2800);
WIRE 16 -1 (-800 2850)(-1100 2850);
WIRE 16 -1 (-800 2800)(-800 2750);
WIRE 16 -1 (-800 2800)(-1100 2800);
WIRE 16 -1 (-800 2750)(-800 2700);
WIRE 16 -1 (-800 2750)(-1100 2750);
WIRE 16 -1 (-800 2700)(-800 2650);
WIRE 16 -1 (-800 2700)(-1100 2700);
WIRE 16 -1 (-800 2650)(-800 2600);
WIRE 16 -1 (-800 2650)(-1100 2650);
WIRE 16 -1 (-800 2600)(-800 2550);
WIRE 16 -1 (-800 2600)(-1100 2600);
WIRE 16 -1 (-800 2550)(-800 2500);
WIRE 16 -1 (-800 2550)(-1100 2550);
WIRE 16 -1 (-800 2500)(-800 2450);
WIRE 16 -1 (-800 2500)(-1100 2500);
WIRE 16 -1 (-800 2450)(-800 2400);
WIRE 16 -1 (-800 2450)(-1100 2450);
WIRE 16 -1 (-800 2400)(-800 2350);
WIRE 16 -1 (-800 2400)(-1100 2400);
WIRE 16 -1 (-800 2350)(-800 2300);
WIRE 16 -1 (-800 2350)(-1100 2350);
WIRE 16 -1 (-800 2300)(-800 2250);
WIRE 16 -1 (-800 2300)(-1100 2300);
WIRE 16 -1 (-800 2250)(-800 2200);
WIRE 16 -1 (-800 2250)(-1100 2250);
WIRE 16 -1 (-800 2200)(-800 2150);
WIRE 16 -1 (-800 2200)(-1100 2200);
WIRE 16 -1 (-800 2150)(-800 2100);
WIRE 16 -1 (-800 2150)(-1100 2150);
WIRE 16 -1 (-800 2100)(-800 2050);
WIRE 16 -1 (-800 2100)(-1100 2100);
WIRE 16 -1 (-800 2050)(-800 2000);
WIRE 16 -1 (-800 2050)(-1100 2050);
WIRE 16 -1 (-800 2000)(-800 1950);
WIRE 16 -1 (-800 2000)(-1100 2000);
WIRE 16 -1 (-800 1950)(-800 1900);
WIRE 16 -1 (-800 1950)(-1100 1950);
WIRE 16 -1 (-800 1900)(-800 1850);
WIRE 16 -1 (-800 1900)(-1100 1900);
WIRE 16 -1 (-800 1850)(-800 1800);
WIRE 16 -1 (-800 1850)(-1100 1850);
WIRE 16 -1 (-800 1800)(-800 1750);
WIRE 16 -1 (-800 1800)(-1100 1800);
WIRE 16 -1 (-800 1750)(-800 1700);
WIRE 16 -1 (-800 1750)(-1100 1750);
WIRE 16 -1 (-800 1700)(-800 1650);
WIRE 16 -1 (-800 1700)(-1100 1700);
WIRE 16 -1 (-800 1650)(-800 1600);
WIRE 16 -1 (-800 1650)(-1100 1650);
WIRE 16 -1 (-800 1600)(-800 1550);
WIRE 16 -1 (-800 1600)(-1100 1600);
WIRE 16 -1 (-800 1550)(-800 1450);
WIRE 16 -1 (-800 1550)(-1100 1550);
WIRE 16 -1 (-800 1450)(-800 1400);
WIRE 16 -1 (-800 1450)(-1100 1450);
WIRE 16 -1 (-800 1400)(-1100 1400);
WIRE 16 -1 (-250 4825)(-250 4725);
WIRE 16 -1 (-250 4725)(-250 4675);
WIRE 16 -1 (150 4725)(-250 4725);
WIRE 16 -1 (-250 4675)(-250 4625);
WIRE 16 -1 (150 4675)(-250 4675);
WIRE 16 -1 (-250 4625)(-250 4575);
WIRE 16 -1 (150 4625)(-250 4625);
WIRE 16 -1 (-250 4575)(-250 4525);
WIRE 16 -1 (150 4575)(-250 4575);
WIRE 16 -1 (-250 4525)(-250 4475);
WIRE 16 -1 (150 4525)(-250 4525);
WIRE 16 -1 (-250 4475)(-250 4425);
WIRE 16 -1 (150 4475)(-250 4475);
WIRE 16 -1 (-250 4425)(-250 4375);
WIRE 16 -1 (150 4425)(-250 4425);
WIRE 16 -1 (-250 4375)(-250 4325);
WIRE 16 -1 (150 4375)(-250 4375);
WIRE 16 -1 (-250 4325)(-250 4275);
WIRE 16 -1 (150 4325)(-250 4325);
WIRE 16 -1 (-250 4275)(-250 4225);
WIRE 16 -1 (150 4275)(-250 4275);
WIRE 16 -1 (-250 4225)(-250 4175);
WIRE 16 -1 (150 4225)(-250 4225);
WIRE 16 -1 (-250 4175)(-250 4125);
WIRE 16 -1 (150 4175)(-250 4175);
WIRE 16 -1 (-250 4125)(-250 4075);
WIRE 16 -1 (150 4125)(-250 4125);
WIRE 16 -1 (-250 4075)(-250 4025);
WIRE 16 -1 (150 4075)(-250 4075);
WIRE 16 -1 (-250 4025)(-250 3975);
WIRE 16 -1 (150 4025)(-250 4025);
WIRE 16 -1 (-250 3975)(-250 3925);
WIRE 16 -1 (150 3975)(-250 3975);
WIRE 16 -1 (-250 3925)(-250 3875);
WIRE 16 -1 (150 3925)(-250 3925);
WIRE 16 -1 (-250 3875)(-250 3825);
WIRE 16 -1 (150 3875)(-250 3875);
WIRE 16 -1 (-250 3825)(-250 3775);
WIRE 16 -1 (150 3825)(-250 3825);
WIRE 16 -1 (-250 3775)(-250 3725);
WIRE 16 -1 (150 3775)(-250 3775);
WIRE 16 -1 (-250 3725)(-250 3675);
WIRE 16 -1 (150 3725)(-250 3725);
WIRE 16 -1 (-250 3675)(-250 3625);
WIRE 16 -1 (150 3675)(-250 3675);
WIRE 16 -1 (-250 3625)(-250 3575);
WIRE 16 -1 (150 3625)(-250 3625);
WIRE 16 -1 (-250 3575)(-250 3525);
WIRE 16 -1 (150 3575)(-250 3575);
WIRE 16 -1 (-250 3525)(-250 3475);
WIRE 16 -1 (150 3525)(-250 3525);
WIRE 16 -1 (-250 3475)(-250 3425);
WIRE 16 -1 (150 3475)(-250 3475);
WIRE 16 -1 (-250 3425)(-250 3375);
WIRE 16 -1 (150 3425)(-250 3425);
WIRE 16 -1 (-250 3375)(-250 3325);
WIRE 16 -1 (150 3375)(-250 3375);
WIRE 16 -1 (-250 3325)(-250 3275);
WIRE 16 -1 (150 3325)(-250 3325);
WIRE 16 -1 (-250 3275)(-250 3225);
WIRE 16 -1 (150 3275)(-250 3275);
WIRE 16 -1 (-250 3225)(-250 3175);
WIRE 16 -1 (150 3225)(-250 3225);
WIRE 16 -1 (-250 3175)(-250 3125);
WIRE 16 -1 (150 3175)(-250 3175);
WIRE 16 -1 (-250 3125)(-250 3075);
WIRE 16 -1 (150 3125)(-250 3125);
WIRE 16 -1 (-250 3075)(-250 3025);
WIRE 16 -1 (150 3075)(-250 3075);
WIRE 16 -1 (-250 3025)(-250 2975);
WIRE 16 -1 (150 3025)(-250 3025);
WIRE 16 -1 (-250 2975)(-250 2925);
WIRE 16 -1 (150 2975)(-250 2975);
WIRE 16 -1 (-250 2925)(-250 2875);
WIRE 16 -1 (150 2925)(-250 2925);
WIRE 16 -1 (-250 2875)(-250 2825);
WIRE 16 -1 (150 2875)(-250 2875);
WIRE 16 -1 (-250 2825)(-250 2775);
WIRE 16 -1 (150 2825)(-250 2825);
WIRE 16 -1 (-250 2775)(-250 2725);
WIRE 16 -1 (150 2775)(-250 2775);
WIRE 16 -1 (-250 2725)(-250 2675);
WIRE 16 -1 (150 2725)(-250 2725);
WIRE 16 -1 (-250 2675)(-250 2625);
WIRE 16 -1 (150 2675)(-250 2675);
WIRE 16 -1 (-250 2625)(-250 2575);
WIRE 16 -1 (150 2625)(-250 2625);
WIRE 16 -1 (-250 2575)(-250 2525);
WIRE 16 -1 (150 2575)(-250 2575);
WIRE 16 -1 (-250 2525)(-250 2475);
WIRE 16 -1 (150 2525)(-250 2525);
WIRE 16 -1 (-250 2475)(-250 2425);
WIRE 16 -1 (150 2475)(-250 2475);
WIRE 16 -1 (-250 2425)(-250 2375);
WIRE 16 -1 (150 2425)(-250 2425);
WIRE 16 -1 (-250 2375)(-250 2325);
WIRE 16 -1 (150 2375)(-250 2375);
WIRE 16 -1 (-250 2325)(-250 2275);
WIRE 16 -1 (150 2325)(-250 2325);
WIRE 16 -1 (-250 2275)(-250 2225);
WIRE 16 -1 (150 2275)(-250 2275);
WIRE 16 -1 (-250 2225)(-250 2175);
WIRE 16 -1 (150 2225)(-250 2225);
WIRE 16 -1 (-250 2175)(-250 2125);
WIRE 16 -1 (150 2175)(-250 2175);
WIRE 16 -1 (-250 2125)(-250 2075);
WIRE 16 -1 (150 2125)(-250 2125);
WIRE 16 -1 (-250 2075)(-250 2025);
WIRE 16 -1 (150 2075)(-250 2075);
WIRE 16 -1 (-250 2025)(-250 1975);
WIRE 16 -1 (150 2025)(-250 2025);
WIRE 16 -1 (-250 1975)(-250 1925);
WIRE 16 -1 (150 1975)(-250 1975);
WIRE 16 -1 (-250 1925)(-250 1875);
WIRE 16 -1 (150 1925)(-250 1925);
WIRE 16 -1 (-250 1875)(-250 1825);
WIRE 16 -1 (150 1875)(-250 1875);
WIRE 16 -1 (-250 1825)(-250 1775);
WIRE 16 -1 (150 1825)(-250 1825);
WIRE 16 -1 (-250 1775)(-250 1725);
WIRE 16 -1 (150 1775)(-250 1775);
WIRE 16 -1 (-250 1725)(-250 1675);
WIRE 16 -1 (150 1725)(-250 1725);
WIRE 16 -1 (-250 1675)(-250 1625);
WIRE 16 -1 (150 1675)(-250 1675);
WIRE 16 -1 (-250 1625)(-250 1575);
WIRE 16 -1 (150 1625)(-250 1625);
WIRE 16 -1 (-250 1575)(-250 1525);
WIRE 16 -1 (150 1575)(-250 1575);
WIRE 16 -1 (-250 1525)(-250 1475);
WIRE 16 -1 (150 1525)(-250 1525);
WIRE 16 -1 (-250 1475)(-250 1425);
WIRE 16 -1 (150 1475)(-250 1475);
WIRE 16 -1 (-250 1425)(-250 1375);
WIRE 16 -1 (150 1425)(-250 1425);
WIRE 16 -1 (-250 1375)(-250 1325);
WIRE 16 -1 (150 1375)(-250 1375);
WIRE 16 -1 (-250 1325)(-250 1275);
WIRE 16 -1 (150 1325)(-250 1325);
WIRE 16 -1 (-250 1275)(-250 1225);
WIRE 16 -1 (150 1275)(-250 1275);
WIRE 16 -1 (-250 1225)(-250 1175);
WIRE 16 -1 (150 1225)(-250 1225);
WIRE 16 -1 (-250 1175)(-250 1125);
WIRE 16 -1 (150 1175)(-250 1175);
WIRE 16 -1 (-250 1125)(-250 1075);
WIRE 16 -1 (150 1125)(-250 1125);
WIRE 16 -1 (-250 1075)(-250 1025);
WIRE 16 -1 (150 1075)(-250 1075);
WIRE 16 -1 (150 1025)(-250 1025);
WIRE 16 -1 (3000 1250)(3000 1225);
WIRE 16 -1 (2450 1125)(2450 1075);
WIRE 16 -1 (2450 1075)(2175 1075);
WIRE 16 -1 (2175 1125)(2175 1075);
WIRE 16 -1 (2175 1075)(2175 1025);
WIRE 16 -1 (1950 1075)(2175 1075);
WIRE 16 -1 (2175 1025)(2175 975);
WIRE 16 -1 (1950 1025)(2175 1025);
WIRE 16 -1 (2175 1175)(2175 1125);
WIRE 16 -1 (1950 1125)(2175 1125);
WIRE 16 -1 (1950 1175)(2175 1175);
WIRE 16 -1 (2175 975)(2175 925);
WIRE 16 -1 (1950 975)(2175 975);
WIRE 16 -1 (2175 925)(2175 825);
WIRE 16 -1 (1950 925)(2175 925);
WIRE 16 -1 (2175 825)(2175 775);
WIRE 16 -1 (2175 825)(1950 825);
WIRE 16 -1 (2175 775)(2175 725);
WIRE 16 -1 (2175 775)(1950 775);
WIRE 16 -1 (2175 725)(2175 675);
WIRE 16 -1 (2175 725)(1950 725);
WIRE 16 -1 (2175 675)(1950 675);
WIRE 16 -1 (2150 4900)(2150 4725);
WIRE 16 -1 (2150 4675)(2150 4725);
WIRE 16 -1 (1950 4725)(2150 4725);
WIRE 16 -1 (2150 4675)(2150 4625);
WIRE 16 -1 (1950 4675)(2150 4675);
WIRE 16 -1 (2150 4575)(2150 4625);
WIRE 16 -1 (1950 4625)(2150 4625);
WIRE 16 -1 (2150 4525)(2150 4575);
WIRE 16 -1 (1950 4575)(2150 4575);
WIRE 16 -1 (2150 4475)(2150 4525);
WIRE 16 -1 (1950 4525)(2150 4525);
WIRE 16 -1 (2150 4425)(2150 4475);
WIRE 16 -1 (1950 4475)(2150 4475);
WIRE 16 -1 (2150 4375)(2150 4425);
WIRE 16 -1 (1950 4425)(2150 4425);
WIRE 16 -1 (2150 4325)(2150 4375);
WIRE 16 -1 (1950 4375)(2150 4375);
WIRE 16 -1 (2150 4275)(2150 4325);
WIRE 16 -1 (1950 4325)(2150 4325);
WIRE 16 -1 (2150 4225)(2150 4275);
WIRE 16 -1 (1950 4275)(2150 4275);
WIRE 16 -1 (2150 4175)(2150 4225);
WIRE 16 -1 (1950 4225)(2150 4225);
WIRE 16 -1 (2150 4125)(2150 4175);
WIRE 16 -1 (1950 4175)(2150 4175);
WIRE 16 -1 (2150 4075)(2150 4125);
WIRE 16 -1 (1950 4125)(2150 4125);
WIRE 16 -1 (2150 4025)(2150 4075);
WIRE 16 -1 (1950 4075)(2150 4075);
WIRE 16 -1 (2150 3975)(2150 4025);
WIRE 16 -1 (1950 4025)(2150 4025);
WIRE 16 -1 (2150 3925)(2150 3975);
WIRE 16 -1 (1950 3975)(2150 3975);
WIRE 16 -1 (2150 3875)(2150 3925);
WIRE 16 -1 (1950 3925)(2150 3925);
WIRE 16 -1 (2150 3825)(2150 3875);
WIRE 16 -1 (1950 3875)(2150 3875);
WIRE 16 -1 (2150 3775)(2150 3825);
WIRE 16 -1 (1950 3825)(2150 3825);
WIRE 16 -1 (2150 3725)(2150 3775);
WIRE 16 -1 (1950 3775)(2150 3775);
WIRE 16 -1 (2150 3675)(2150 3725);
WIRE 16 -1 (1950 3725)(2150 3725);
WIRE 16 -1 (2150 3625)(2150 3675);
WIRE 16 -1 (1950 3675)(2150 3675);
WIRE 16 -1 (2150 3575)(2150 3625);
WIRE 16 -1 (1950 3625)(2150 3625);
WIRE 16 -1 (2150 3525)(2150 3575);
WIRE 16 -1 (1950 3575)(2150 3575);
WIRE 16 -1 (2150 3475)(2150 3525);
WIRE 16 -1 (1950 3525)(2150 3525);
WIRE 16 -1 (1950 3475)(2150 3475);
WIRE 16 -1 (2500 2675)(2500 2600);
WIRE 16 -1 (2150 2600)(2500 2600);
WIRE 16 -1 (2150 2575)(2150 2600);
WIRE 16 -1 (2150 2600)(2150 2625);
WIRE 16 -1 (2150 2625)(2150 2675);
WIRE 16 -1 (1950 2625)(2150 2625);
WIRE 16 -1 (2150 2575)(2150 2525);
WIRE 16 -1 (1950 2575)(2150 2575);
WIRE 16 -1 (2150 2525)(2150 2475);
WIRE 16 -1 (1950 2525)(2150 2525);
WIRE 16 -1 (1950 2675)(2150 2675);
WIRE 16 -1 (2150 2475)(2150 2425);
WIRE 16 -1 (1950 2475)(2150 2475);
WIRE 16 -1 (2150 2425)(2150 2325);
WIRE 16 -1 (1950 2425)(2150 2425);
WIRE 16 -1 (2150 2325)(2150 2275);
WIRE 16 -1 (1950 2325)(2150 2325);
WIRE 16 -1 (2150 2275)(2150 2225);
WIRE 16 -1 (1950 2275)(2150 2275);
WIRE 16 -1 (2150 2225)(2150 2175);
WIRE 16 -1 (1950 2225)(2150 2225);
WIRE 16 -1 (2150 2125)(2150 2175);
WIRE 16 -1 (2150 2175)(1950 2175);
WIRE 16 -1 (2150 2125)(2150 2075);
WIRE 16 -1 (1950 2125)(2150 2125);
WIRE 16 -1 (2150 2075)(2150 2025);
WIRE 16 -1 (1950 2075)(2150 2075);
WIRE 16 -1 (2150 2025)(2150 1975);
WIRE 16 -1 (1950 2025)(2150 2025);
WIRE 16 -1 (2150 1975)(2150 1925);
WIRE 16 -1 (1950 1975)(2150 1975);
WIRE 16 -1 (2150 1925)(2150 1875);
WIRE 16 -1 (1950 1925)(2150 1925);
WIRE 16 -1 (1950 1875)(2150 1875);
WIRE 16 -1 (2500 3400)(2500 3300);
WIRE 16 -1 (2500 3300)(2150 3300);
WIRE 16 -1 (2150 3275)(2150 3300);
WIRE 16 -1 (2150 3300)(2150 3325);
WIRE 16 -1 (2150 3375)(2150 3325);
WIRE 16 -1 (1950 3325)(2150 3325);
WIRE 16 -1 (2150 3275)(2150 3225);
WIRE 16 -1 (1950 3275)(2150 3275);
WIRE 16 -1 (2150 3225)(2150 3175);
WIRE 16 -1 (1950 3225)(2150 3225);
WIRE 16 -1 (1950 3375)(2150 3375);
WIRE 16 -1 (2150 3175)(2150 3125);
WIRE 16 -1 (1950 3175)(2150 3175);
WIRE 16 -1 (2150 3125)(2150 3075);
WIRE 16 -1 (1950 3125)(2150 3125);
WIRE 16 -1 (2150 3075)(2150 3025);
WIRE 16 -1 (1950 3075)(2150 3075);
WIRE 16 -1 (2150 3025)(2150 2975);
WIRE 16 -1 (1950 3025)(2150 3025);
WIRE 16 -1 (2150 2975)(2150 2925);
WIRE 16 -1 (1950 2975)(2150 2975);
WIRE 16 -1 (2150 2925)(2150 2875);
WIRE 16 -1 (1950 2925)(2150 2925);
WIRE 16 -1 (2150 2875)(2150 2825);
WIRE 16 -1 (1950 2875)(2150 2875);
WIRE 16 -1 (2150 2825)(2150 2775);
WIRE 16 -1 (1950 2825)(2150 2825);
WIRE 16 -1 (1950 2775)(2150 2775);
WIRE 16 -1 (2325 1775)(2325 1975);
WIRE 16 -1 (2325 1725)(2325 1775);
WIRE 16 -1 (1950 1775)(2325 1775);
WIRE 16 -1 (2325 1675)(2325 1725);
WIRE 16 -1 (1950 1725)(2325 1725);
WIRE 16 -1 (2325 1625)(2325 1675);
WIRE 16 -1 (1950 1675)(2325 1675);
WIRE 16 -1 (1950 1625)(2325 1625);
WIRE 16 -1 (3000 1550)(3000 1525);
WIRE 16 -1 (2175 1525)(3000 1525);
WIRE 16 -1 (3000 1450)(3000 1525);
WIRE 16 -1 (2175 1475)(2175 1525);
WIRE 16 -1 (2175 1525)(1950 1525);
WIRE 16 -1 (2175 1425)(2175 1475);
WIRE 16 -1 (2175 1475)(1950 1475);
WIRE 16 -1 (2175 1425)(2175 1375);
WIRE 16 -1 (2175 1425)(1950 1425);
WIRE 16 -1 (2175 1375)(1950 1375);
WIRE 16 -1 (2450 1325)(2450 1275);
WIRE 16 -1 (2450 1275)(1950 1275);
DOT 1 (-3075 2850);
DOT 1 (-250 3825);
DOT 1 (2175 1425);
DOT 1 (2175 1475);
DOT 1 (2150 1925);
DOT 1 (-250 1225);
DOT 1 (2150 2075);
DOT 1 (2325 1725);
DOT 1 (2325 1775);
DOT 1 (-250 4325);
DOT 1 (-250 3775);
DOT 1 (2175 1075);
DOT 1 (2150 2600);
DOT 1 (-3075 3750);
DOT 1 (2150 3925);
DOT 1 (-800 3100);
DOT 1 (-800 3050);
DOT 1 (-800 3000);
DOT 1 (2175 775);
DOT 1 (-800 1450);
DOT 1 (-800 1650);
DOT 1 (-800 1750);
DOT 1 (2150 2325);
DOT 1 (-250 2475);
DOT 1 (-250 4525);
DOT 1 (2150 4675);
DOT 1 (-3075 2100);
DOT 1 (-800 1600);
DOT 1 (-800 1850);
DOT 1 (-800 1800);
DOT 1 (-800 1700);
DOT 1 (-800 1950);
DOT 1 (-800 1900);
DOT 1 (-800 2000);
DOT 1 (-800 2100);
DOT 1 (-800 2150);
DOT 1 (-800 2200);
DOT 1 (-800 2250);
DOT 1 (-800 2300);
DOT 1 (-800 2350);
DOT 1 (-800 2400);
DOT 1 (-800 2450);
DOT 1 (-800 2500);
DOT 1 (-800 2800);
DOT 1 (-800 2850);
DOT 1 (-800 2900);
DOT 1 (-800 2950);
DOT 1 (-800 3150);
DOT 1 (-800 3200);
DOT 1 (-800 3250);
DOT 1 (-800 3300);
DOT 1 (-800 3350);
DOT 1 (-800 3400);
DOT 1 (-800 3450);
DOT 1 (-800 3500);
DOT 1 (-800 3550);
DOT 1 (-800 3600);
DOT 1 (-800 3650);
DOT 1 (-800 3750);
DOT 1 (-800 3800);
DOT 1 (-800 3850);
DOT 1 (-800 3900);
DOT 1 (-800 3950);
DOT 1 (-3075 1600);
DOT 1 (-3075 1650);
DOT 1 (-3075 1700);
DOT 1 (-3075 1750);
DOT 1 (-3075 1800);
DOT 1 (-3075 1850);
DOT 1 (-3075 1900);
DOT 1 (-3075 1950);
DOT 1 (-3075 2000);
DOT 1 (-3075 2050);
DOT 1 (-3075 2150);
DOT 1 (-3075 2200);
DOT 1 (-3075 2250);
DOT 1 (-3075 2300);
DOT 1 (-3075 2350);
DOT 1 (-3075 2400);
DOT 1 (-3075 2450);
DOT 1 (-3075 2500);
DOT 1 (-3075 2550);
DOT 1 (-3075 2600);
DOT 1 (-3075 2650);
DOT 1 (-3075 2700);
DOT 1 (-3075 2750);
DOT 1 (-3075 2800);
DOT 1 (-3075 2900);
DOT 1 (-3075 2950);
DOT 1 (-3075 3000);
DOT 1 (-3075 3050);
DOT 1 (-3075 3100);
DOT 1 (-3075 3150);
DOT 1 (-3075 3200);
DOT 1 (-3075 3300);
DOT 1 (-3075 3350);
DOT 1 (-3075 3400);
DOT 1 (-3075 3450);
DOT 1 (-3075 3500);
DOT 1 (-3075 3550);
DOT 1 (-3075 3600);
DOT 1 (-3075 3650);
DOT 1 (-3075 3700);
DOT 1 (-3075 3800);
DOT 1 (-3075 3900);
DOT 1 (-3075 3950);
DOT 1 (-250 1375);
DOT 1 (-250 1425);
DOT 1 (-250 1325);
DOT 1 (-250 1475);
DOT 1 (-250 1525);
DOT 1 (-250 1675);
DOT 1 (-250 1725);
DOT 1 (-250 1925);
DOT 1 (-250 1875);
DOT 1 (-250 1825);
DOT 1 (-250 1775);
DOT 1 (-250 2075);
DOT 1 (-250 2125);
DOT 1 (-250 2175);
DOT 1 (-250 2375);
DOT 1 (-250 2275);
DOT 1 (-250 2425);
DOT 1 (-250 2225);
DOT 1 (-250 2675);
DOT 1 (-250 2875);
DOT 1 (-250 2925);
DOT 1 (-250 2775);
DOT 1 (-250 2725);
DOT 1 (-250 2975);
DOT 1 (-250 3125);
DOT 1 (-250 3075);
DOT 1 (-250 3025);
DOT 1 (-250 3175);
DOT 1 (-250 3225);
DOT 1 (-250 3375);
DOT 1 (-250 3325);
DOT 1 (-250 3275);
DOT 1 (-250 3425);
DOT 1 (-250 3475);
DOT 1 (-250 3675);
DOT 1 (-250 3725);
DOT 1 (-250 3525);
DOT 1 (-250 3575);
DOT 1 (-250 3925);
DOT 1 (-250 3975);
DOT 1 (-250 3875);
DOT 1 (-250 4075);
DOT 1 (-250 4125);
DOT 1 (-250 4175);
DOT 1 (-250 4225);
DOT 1 (-250 4025);
DOT 1 (2150 3025);
DOT 1 (2150 3075);
DOT 1 (2150 3175);
DOT 1 (2150 3125);
DOT 1 (2150 3575);
DOT 1 (2150 3625);
DOT 1 (2150 3675);
DOT 1 (2150 3725);
DOT 1 (2150 3825);
DOT 1 (2150 3775);
DOT 1 (2150 3875);
DOT 1 (2150 3975);
DOT 1 (2150 4075);
DOT 1 (2150 4025);
DOT 1 (2150 4125);
DOT 1 (2150 4175);
DOT 1 (2150 4225);
DOT 1 (-250 4475);
DOT 1 (-250 4425);
DOT 1 (-250 4375);
DOT 1 (-250 4275);
DOT 1 (-250 4575);
DOT 1 (-250 4625);
DOT 1 (2150 4325);
DOT 1 (2150 4275);
DOT 1 (2150 4375);
DOT 1 (2150 4425);
DOT 1 (2150 4475);
DOT 1 (-250 4675);
DOT 1 (-250 4725);
DOT 1 (-250 1625);
DOT 1 (-250 1275);
DOT 1 (2150 4525);
DOT 1 (2150 4575);
DOT 1 (2150 4625);
DOT 1 (2150 4725);
DOT 1 (2150 3225);
DOT 1 (-250 2825);
DOT 1 (-800 3700);
DOT 1 (-250 2025);
DOT 1 (-250 1075);
DOT 1 (2175 925);
DOT 1 (2175 825);
DOT 1 (-3075 1550);
DOT 1 (-3075 1450);
DOT 1 (-3075 1400);
DOT 1 (-250 1175);
DOT 1 (2150 1975);
DOT 1 (-250 1975);
DOT 1 (-800 2050);
DOT 1 (-250 1575);
DOT 1 (-250 2625);
DOT 1 (-250 2575);
DOT 1 (-250 2525);
DOT 1 (2150 3525);
DOT 1 (2150 3275);
DOT 1 (2150 3300);
DOT 1 (2150 2975);
DOT 1 (2150 3325);
DOT 1 (2150 2175);
DOT 1 (2150 2225);
DOT 1 (2150 2275);
DOT 1 (2150 2425);
DOT 1 (2150 2475);
DOT 1 (2150 2525);
DOT 1 (2150 2575);
DOT 1 (2150 2625);
DOT 1 (2150 2825);
DOT 1 (2150 2875);
DOT 1 (2150 2925);
DOT 1 (2175 725);
DOT 1 (-250 2325);
DOT 1 (-3075 3250);
DOT 1 (-800 2550);
DOT 1 (-800 2600);
DOT 1 (-800 2650);
DOT 1 (-800 2700);
DOT 1 (-800 2750);
DOT 1 (2150 2025);
DOT 1 (2150 2125);
DOT 1 (-250 1125);
DOT 1 (-250 3625);
DOT 1 (-3075 3850);
DOT 1 (2325 1675);
DOT 1 (2175 1125);
DOT 1 (2175 1025);
DOT 1 (2175 975);
DOT 1 (-800 1550);
DOT 1 (2175 1525);
DOT 1 (3000 1525);
FORCENOTE
SKYLAKE - SKT0 - 18 OF 21
(2450 300) 0;
DISPLAY LEFT (2450 300);
DISPLAY 1.021277 (2450 300);
PAINT RED (2450 300);
FORCENOTE
ROOM=CPU0
(-3725 450) 0;
DISPLAY LEFT (-3725 450);
DISPLAY 1.723404 (-3725 450);
PAINT PURPLE (-3725 450);
FORCENOTE
BOM_COST=PROC_SOCKET
(-3775 300) 0;
DISPLAY LEFT (-3775 300);
DISPLAY 1.723404 (-3775 300);
PAINT PURPLE (-3775 300);
FORCENOTE
TP FAB4 ADD ATTRIBUTE GROUP=PWR_MCP_CAP 20170508
(2950 1050) 0;
DISPLAY LEFT (2950 1050);
DISPLAY 0.638298 (2950 1050);
PAINT RED (2950 1050);
QUIT
